FILE_TYPE = MACRO_DRAWING;
SET COLOR_WIRE YELLOW;
SET COLOR_PROP MONO;
SET COLOR_DOT WHITE;
SET COLOR_ARC YELLOW;
SET COLOR_BODY GREEN;
SET COLOR_NOTE MONO;
SET PROP_DISPLAY VALUE;
SET PAGE_NUMBER P144;
FORCEADD OFFPAGE..5
(-6650 -1900);
FORCEPROP 2 LAST $XR0 160 
J 0
(-6935 -1900);
DISPLAY 0.638298 (-6935 -1900);
PAINT MONO (-6935 -1900);
FORCEPROP 1 LAST COMMENT_BODY TRUE
J 0
(-6550 -1975);
DISPLAY 0.872340 (-6550 -1975);
PAINT GREEN (-6550 -1975);
DISPLAY INVISIBLE (-6550 -1975);
FORCEPROP 1 LAST OFFPAGE TRUE
J 0
(-6325 -2025);
DISPLAY 0.872340 (-6325 -2025);
PAINT GREEN (-6325 -2025);
DISPLAY INVISIBLE (-6325 -2025);
FORCEPROP 2 LAST CDS_LIB mstr_standard
J 0
(-6650 -1900);
PAINT MONO (-6650 -1900);
DISPLAY INVISIBLE (-6650 -1900);
FORCEPROP 2 LAST PATH I24
J 0
(-6600 -1825);
DISPLAY 1.021277 (-6600 -1825);
PAINT ORANGE (-6600 -1825);
DISPLAY INVISIBLE (-6600 -1825);
FORCEADD OFFPAGE..3
R 2
(-6625 -1850);
FORCEPROP 2 LAST $XR0 160 
J 0
(-6935 -1850);
DISPLAY 0.638298 (-6935 -1850);
PAINT MONO (-6935 -1850);
FORCEPROP 1 LAST COMMENT_BODY TRUE
J 2
(-6575 -1950);
DISPLAY 1.170213 (-6575 -1950);
PAINT GREEN (-6575 -1950);
DISPLAY INVISIBLE (-6575 -1950);
FORCEPROP 1 LAST OFFPAGE TRUE
J 2
(-6950 -1975);
PAINT GREEN (-6950 -1975);
DISPLAY INVISIBLE (-6950 -1975);
FORCEPROP 2 LAST BOM_COST SM_CONTROLLER
J 2
(-7100 -1800);
PAINT MONO (-7100 -1800);
DISPLAY INVISIBLE (-7100 -1800);
FORCEPROP 2 LAST ROOM BMC
J 2
(-7100 -1800);
PAINT MONO (-7100 -1800);
DISPLAY INVISIBLE (-7100 -1800);
FORCEPROP 2 LAST PATH I25
J 0
(-6575 -1775);
DISPLAY 1.021277 (-6575 -1775);
PAINT ORANGE (-6575 -1775);
DISPLAY INVISIBLE (-6575 -1775);
FORCEPROP 2 LAST CDS_LIB mstr_standard
J 0
(-6625 -1850);
PAINT MONO (-6625 -1850);
DISPLAY INVISIBLE (-6625 -1850);
FORCEADD OFFPAGE..3
R 2
(-6625 -2150);
FORCEPROP 2 LAST $XR0 159 
J 0
(-6935 -2150);
DISPLAY 0.638298 (-6935 -2150);
PAINT MONO (-6935 -2150);
FORCEPROP 1 LAST COMMENT_BODY TRUE
J 2
(-6575 -2250);
DISPLAY 1.170213 (-6575 -2250);
PAINT GREEN (-6575 -2250);
DISPLAY INVISIBLE (-6575 -2250);
FORCEPROP 1 LAST OFFPAGE TRUE
J 2
(-6950 -2275);
PAINT GREEN (-6950 -2275);
DISPLAY INVISIBLE (-6950 -2275);
FORCEPROP 2 LAST ROOM BMC
J 2
(-7100 -2100);
PAINT MONO (-7100 -2100);
DISPLAY INVISIBLE (-7100 -2100);
FORCEPROP 2 LAST BOM_COST SM_CONTROLLER
J 2
(-7100 -2100);
PAINT MONO (-7100 -2100);
DISPLAY INVISIBLE (-7100 -2100);
FORCEPROP 2 LAST PATH I26
J 0
(-6575 -2075);
DISPLAY 1.021277 (-6575 -2075);
PAINT ORANGE (-6575 -2075);
DISPLAY INVISIBLE (-6575 -2075);
FORCEPROP 2 LAST CDS_LIB mstr_standard
J 0
(-6625 -2150);
PAINT MONO (-6625 -2150);
DISPLAY INVISIBLE (-6625 -2150);
FORCEADD OFFPAGE..5
(-6650 -2200);
FORCEPROP 2 LAST $XR0 159 
J 0
(-6935 -2200);
DISPLAY 0.638298 (-6935 -2200);
PAINT MONO (-6935 -2200);
FORCEPROP 1 LAST COMMENT_BODY TRUE
J 0
(-6550 -2275);
DISPLAY 0.872340 (-6550 -2275);
PAINT GREEN (-6550 -2275);
DISPLAY INVISIBLE (-6550 -2275);
FORCEPROP 1 LAST OFFPAGE TRUE
J 0
(-6325 -2325);
DISPLAY 0.872340 (-6325 -2325);
PAINT GREEN (-6325 -2325);
DISPLAY INVISIBLE (-6325 -2325);
FORCEPROP 2 LAST PATH I27
J 0
(-6600 -2125);
DISPLAY 1.021277 (-6600 -2125);
PAINT ORANGE (-6600 -2125);
DISPLAY INVISIBLE (-6600 -2125);
FORCEPROP 2 LAST CDS_LIB mstr_standard
J 0
(-6650 -2200);
PAINT MONO (-6650 -2200);
DISPLAY INVISIBLE (-6650 -2200);
FORCEADD OFFPAGE..5
(-6625 -2050);
FORCEPROP 2 LAST $XR0 159 
J 0
(-6910 -2050);
DISPLAY 0.638298 (-6910 -2050);
PAINT MONO (-6910 -2050);
FORCEPROP 1 LAST COMMENT_BODY TRUE
J 0
(-6525 -2125);
DISPLAY 0.872340 (-6525 -2125);
PAINT GREEN (-6525 -2125);
DISPLAY INVISIBLE (-6525 -2125);
FORCEPROP 1 LAST OFFPAGE TRUE
J 0
(-6300 -2175);
DISPLAY 0.872340 (-6300 -2175);
PAINT GREEN (-6300 -2175);
DISPLAY INVISIBLE (-6300 -2175);
FORCEPROP 2 LAST CDS_LIB mstr_standard
J 0
(-6625 -2050);
PAINT MONO (-6625 -2050);
DISPLAY INVISIBLE (-6625 -2050);
FORCEPROP 2 LAST PATH I28
J 0
(-6575 -1975);
DISPLAY 1.021277 (-6575 -1975);
PAINT ORANGE (-6575 -1975);
DISPLAY INVISIBLE (-6575 -1975);
FORCEADD OFFPAGE..3
R 2
(-6625 -2000);
FORCEPROP 2 LAST $XR0 159 
J 0
(-6935 -2000);
DISPLAY 0.638298 (-6935 -2000);
PAINT MONO (-6935 -2000);
FORCEPROP 1 LAST COMMENT_BODY TRUE
J 2
(-6575 -2100);
DISPLAY 1.170213 (-6575 -2100);
PAINT GREEN (-6575 -2100);
DISPLAY INVISIBLE (-6575 -2100);
FORCEPROP 1 LAST OFFPAGE TRUE
J 2
(-6950 -2125);
PAINT GREEN (-6950 -2125);
DISPLAY INVISIBLE (-6950 -2125);
FORCEPROP 2 LAST BOM_COST SM_CONTROLLER
J 2
(-7100 -1950);
PAINT MONO (-7100 -1950);
DISPLAY INVISIBLE (-7100 -1950);
FORCEPROP 2 LAST ROOM BMC
J 2
(-7100 -1950);
PAINT MONO (-7100 -1950);
DISPLAY INVISIBLE (-7100 -1950);
FORCEPROP 2 LAST PATH I29
J 0
(-6575 -1925);
DISPLAY 1.021277 (-6575 -1925);
PAINT ORANGE (-6575 -1925);
DISPLAY INVISIBLE (-6575 -1925);
FORCEPROP 2 LAST CDS_LIB mstr_standard
J 0
(-6625 -2000);
PAINT MONO (-6625 -2000);
DISPLAY INVISIBLE (-6625 -2000);
FORCEADD OFFPAGE..3
R 2
(-6625 -2750);
FORCEPROP 2 LAST $XR0 159 
J 0
(-6935 -2750);
DISPLAY 0.638298 (-6935 -2750);
PAINT MONO (-6935 -2750);
FORCEPROP 1 LAST COMMENT_BODY TRUE
J 2
(-6575 -2850);
DISPLAY 1.170213 (-6575 -2850);
PAINT GREEN (-6575 -2850);
DISPLAY INVISIBLE (-6575 -2850);
FORCEPROP 1 LAST OFFPAGE TRUE
J 2
(-6950 -2875);
PAINT GREEN (-6950 -2875);
DISPLAY INVISIBLE (-6950 -2875);
FORCEPROP 2 LAST BOM_COST SM_CONTROLLER
J 2
(-7100 -2700);
PAINT MONO (-7100 -2700);
DISPLAY INVISIBLE (-7100 -2700);
FORCEPROP 2 LAST ROOM BMC
J 2
(-7100 -2700);
PAINT MONO (-7100 -2700);
DISPLAY INVISIBLE (-7100 -2700);
FORCEPROP 2 LAST PATH I30
J 0
(-6575 -2675);
DISPLAY 1.021277 (-6575 -2675);
PAINT ORANGE (-6575 -2675);
DISPLAY INVISIBLE (-6575 -2675);
FORCEPROP 2 LAST CDS_LIB mstr_standard
J 0
(-6625 -2750);
PAINT MONO (-6625 -2750);
DISPLAY INVISIBLE (-6625 -2750);
FORCEADD OFFPAGE..5
(-6650 -2800);
FORCEPROP 2 LAST $XR0 159 
J 0
(-6935 -2800);
DISPLAY 0.638298 (-6935 -2800);
PAINT MONO (-6935 -2800);
FORCEPROP 1 LAST COMMENT_BODY TRUE
J 0
(-6550 -2875);
DISPLAY 0.872340 (-6550 -2875);
PAINT GREEN (-6550 -2875);
DISPLAY INVISIBLE (-6550 -2875);
FORCEPROP 1 LAST OFFPAGE TRUE
J 0
(-6325 -2925);
DISPLAY 0.872340 (-6325 -2925);
PAINT GREEN (-6325 -2925);
DISPLAY INVISIBLE (-6325 -2925);
FORCEPROP 2 LAST PATH I31
J 0
(-6600 -2725);
DISPLAY 1.021277 (-6600 -2725);
PAINT ORANGE (-6600 -2725);
DISPLAY INVISIBLE (-6600 -2725);
FORCEPROP 2 LAST CDS_LIB mstr_standard
J 0
(-6650 -2800);
PAINT MONO (-6650 -2800);
DISPLAY INVISIBLE (-6650 -2800);
FORCEADD OFFPAGE..5
(-6650 -2650);
FORCEPROP 2 LAST $XR0 159 
J 0
(-6935 -2650);
DISPLAY 0.638298 (-6935 -2650);
PAINT MONO (-6935 -2650);
FORCEPROP 1 LAST COMMENT_BODY TRUE
J 0
(-6550 -2725);
DISPLAY 0.872340 (-6550 -2725);
PAINT GREEN (-6550 -2725);
DISPLAY INVISIBLE (-6550 -2725);
FORCEPROP 1 LAST OFFPAGE TRUE
J 0
(-6325 -2775);
DISPLAY 0.872340 (-6325 -2775);
PAINT GREEN (-6325 -2775);
DISPLAY INVISIBLE (-6325 -2775);
FORCEPROP 2 LAST CDS_LIB mstr_standard
J 0
(-6650 -2650);
PAINT MONO (-6650 -2650);
DISPLAY INVISIBLE (-6650 -2650);
FORCEPROP 2 LAST PATH I32
J 0
(-6600 -2575);
DISPLAY 1.021277 (-6600 -2575);
PAINT ORANGE (-6600 -2575);
DISPLAY INVISIBLE (-6600 -2575);
FORCEADD OFFPAGE..5
(-6650 -2350);
FORCEPROP 2 LAST $XR0 159 
J 0
(-6935 -2350);
DISPLAY 0.638298 (-6935 -2350);
PAINT MONO (-6935 -2350);
FORCEPROP 1 LAST COMMENT_BODY TRUE
J 0
(-6550 -2425);
DISPLAY 0.872340 (-6550 -2425);
PAINT GREEN (-6550 -2425);
DISPLAY INVISIBLE (-6550 -2425);
FORCEPROP 1 LAST OFFPAGE TRUE
J 0
(-6325 -2475);
DISPLAY 0.872340 (-6325 -2475);
PAINT GREEN (-6325 -2475);
DISPLAY INVISIBLE (-6325 -2475);
FORCEPROP 2 LAST CDS_LIB mstr_standard
J 0
(-6650 -2350);
PAINT MONO (-6650 -2350);
DISPLAY INVISIBLE (-6650 -2350);
FORCEPROP 2 LAST PATH I33
J 0
(-6600 -2275);
DISPLAY 1.021277 (-6600 -2275);
PAINT ORANGE (-6600 -2275);
DISPLAY INVISIBLE (-6600 -2275);
FORCEADD OFFPAGE..3
R 2
(-6625 -2300);
FORCEPROP 2 LAST $XR0 159 
J 0
(-6935 -2300);
DISPLAY 0.638298 (-6935 -2300);
PAINT MONO (-6935 -2300);
FORCEPROP 1 LAST COMMENT_BODY TRUE
J 2
(-6575 -2400);
DISPLAY 1.170213 (-6575 -2400);
PAINT GREEN (-6575 -2400);
DISPLAY INVISIBLE (-6575 -2400);
FORCEPROP 1 LAST OFFPAGE TRUE
J 2
(-6950 -2425);
PAINT GREEN (-6950 -2425);
DISPLAY INVISIBLE (-6950 -2425);
FORCEPROP 2 LAST BOM_COST SM_CONTROLLER
J 2
(-7100 -2250);
PAINT MONO (-7100 -2250);
DISPLAY INVISIBLE (-7100 -2250);
FORCEPROP 2 LAST ROOM BMC
J 2
(-7100 -2250);
PAINT MONO (-7100 -2250);
DISPLAY INVISIBLE (-7100 -2250);
FORCEPROP 2 LAST PATH I34
J 0
(-6575 -2225);
DISPLAY 1.021277 (-6575 -2225);
PAINT ORANGE (-6575 -2225);
DISPLAY INVISIBLE (-6575 -2225);
FORCEPROP 2 LAST CDS_LIB mstr_standard
J 0
(-6625 -2300);
PAINT MONO (-6625 -2300);
DISPLAY INVISIBLE (-6625 -2300);
FORCEADD OFFPAGE..5
(-6650 -2500);
FORCEPROP 2 LAST $XR0 167 
J 0
(-6935 -2500);
DISPLAY 0.638298 (-6935 -2500);
PAINT MONO (-6935 -2500);
FORCEPROP 1 LAST COMMENT_BODY TRUE
J 0
(-6550 -2575);
DISPLAY 0.872340 (-6550 -2575);
PAINT GREEN (-6550 -2575);
DISPLAY INVISIBLE (-6550 -2575);
FORCEPROP 1 LAST OFFPAGE TRUE
J 0
(-6325 -2625);
DISPLAY 0.872340 (-6325 -2625);
PAINT GREEN (-6325 -2625);
DISPLAY INVISIBLE (-6325 -2625);
FORCEPROP 2 LAST PATH I35
J 0
(-6600 -2425);
DISPLAY 1.021277 (-6600 -2425);
PAINT ORANGE (-6600 -2425);
DISPLAY INVISIBLE (-6600 -2425);
FORCEPROP 2 LAST CDS_LIB mstr_standard
J 0
(-6650 -2500);
PAINT MONO (-6650 -2500);
DISPLAY INVISIBLE (-6650 -2500);
FORCEADD OFFPAGE..3
R 2
(-6625 -2450);
FORCEPROP 2 LAST $XR0 167 
J 0
(-6935 -2450);
DISPLAY 0.638298 (-6935 -2450);
PAINT MONO (-6935 -2450);
FORCEPROP 1 LAST COMMENT_BODY TRUE
J 2
(-6575 -2550);
DISPLAY 1.170213 (-6575 -2550);
PAINT GREEN (-6575 -2550);
DISPLAY INVISIBLE (-6575 -2550);
FORCEPROP 1 LAST OFFPAGE TRUE
J 2
(-6950 -2575);
PAINT GREEN (-6950 -2575);
DISPLAY INVISIBLE (-6950 -2575);
FORCEPROP 2 LAST ROOM BMC
J 2
(-7100 -2400);
PAINT MONO (-7100 -2400);
DISPLAY INVISIBLE (-7100 -2400);
FORCEPROP 2 LAST BOM_COST SM_CONTROLLER
J 2
(-7100 -2400);
PAINT MONO (-7100 -2400);
DISPLAY INVISIBLE (-7100 -2400);
FORCEPROP 2 LAST PATH I36
J 0
(-6575 -2375);
DISPLAY 1.021277 (-6575 -2375);
PAINT ORANGE (-6575 -2375);
DISPLAY INVISIBLE (-6575 -2375);
FORCEPROP 2 LAST CDS_LIB mstr_standard
J 0
(-6625 -2450);
PAINT MONO (-6625 -2450);
DISPLAY INVISIBLE (-6625 -2450);
FORCEADD OFFPAGE..3
R 2
(-6625 -2600);
FORCEPROP 2 LAST $XR0 159 
J 0
(-6935 -2600);
DISPLAY 0.638298 (-6935 -2600);
PAINT MONO (-6935 -2600);
FORCEPROP 1 LAST COMMENT_BODY TRUE
J 2
(-6575 -2700);
DISPLAY 1.170213 (-6575 -2700);
PAINT GREEN (-6575 -2700);
DISPLAY INVISIBLE (-6575 -2700);
FORCEPROP 1 LAST OFFPAGE TRUE
J 2
(-6950 -2725);
PAINT GREEN (-6950 -2725);
DISPLAY INVISIBLE (-6950 -2725);
FORCEPROP 2 LAST ROOM BMC
J 2
(-7100 -2550);
PAINT MONO (-7100 -2550);
DISPLAY INVISIBLE (-7100 -2550);
FORCEPROP 2 LAST BOM_COST SM_CONTROLLER
J 2
(-7100 -2550);
PAINT MONO (-7100 -2550);
DISPLAY INVISIBLE (-7100 -2550);
FORCEPROP 2 LAST PATH I37
J 0
(-6575 -2525);
DISPLAY 1.021277 (-6575 -2525);
PAINT ORANGE (-6575 -2525);
DISPLAY INVISIBLE (-6575 -2525);
FORCEPROP 2 LAST CDS_LIB mstr_standard
J 0
(-6625 -2600);
PAINT MONO (-6625 -2600);
DISPLAY INVISIBLE (-6625 -2600);
FORCEADD OFFPAGE..3
R 2
(-6625 -1700);
FORCEPROP 2 LAST $XR0 159 
J 0
(-6935 -1700);
DISPLAY 0.638298 (-6935 -1700);
PAINT MONO (-6935 -1700);
FORCEPROP 1 LAST COMMENT_BODY TRUE
J 2
(-6575 -1800);
DISPLAY 1.170213 (-6575 -1800);
PAINT GREEN (-6575 -1800);
DISPLAY INVISIBLE (-6575 -1800);
FORCEPROP 1 LAST OFFPAGE TRUE
J 2
(-6950 -1825);
PAINT GREEN (-6950 -1825);
DISPLAY INVISIBLE (-6950 -1825);
FORCEPROP 2 LAST ROOM BMC
J 2
(-7100 -1650);
PAINT MONO (-7100 -1650);
DISPLAY INVISIBLE (-7100 -1650);
FORCEPROP 2 LAST BOM_COST SM_CONTROLLER
J 2
(-7100 -1650);
PAINT MONO (-7100 -1650);
DISPLAY INVISIBLE (-7100 -1650);
FORCEPROP 2 LAST PATH I4
J 0
(-6575 -1625);
DISPLAY 1.021277 (-6575 -1625);
PAINT ORANGE (-6575 -1625);
DISPLAY INVISIBLE (-6575 -1625);
FORCEPROP 2 LAST CDS_LIB mstr_standard
J 0
(-6625 -1700);
PAINT MONO (-6625 -1700);
DISPLAY INVISIBLE (-6625 -1700);
FORCEADD OFFPAGE..1
(-6625 -3300);
FORCEPROP 2 LAST $XR2 118 
J 0
(-7117 -3300);
DISPLAY 0.638298 (-7117 -3300);
PAINT MONO (-7117 -3300);
FORCEPROP 2 LAST $XR1 191 
J 0
(-6997 -3300);
DISPLAY 0.638298 (-6997 -3300);
PAINT MONO (-6997 -3300);
FORCEPROP 2 LAST $XR0 133 
J 0
(-6877 -3300);
DISPLAY 0.638298 (-6877 -3300);
PAINT MONO (-6877 -3300);
FORCEPROP 1 LAST COMMENT_BODY TRUE
J 0
(-6500 -3400);
DISPLAY 0.872340 (-6500 -3400);
PAINT GREEN (-6500 -3400);
DISPLAY INVISIBLE (-6500 -3400);
FORCEPROP 1 LAST OFFPAGE TRUE
J 0
(-6300 -3425);
DISPLAY 0.872340 (-6300 -3425);
PAINT GREEN (-6300 -3425);
DISPLAY INVISIBLE (-6300 -3425);
FORCEPROP 2 LAST CDS_LIB mstr_standard
J 0
(-6625 -3300);
PAINT MONO (-6625 -3300);
DISPLAY INVISIBLE (-6625 -3300);
FORCEPROP 2 LAST PATH I44
J 0
(-6575 -3225);
DISPLAY 1.021277 (-6575 -3225);
PAINT ORANGE (-6575 -3225);
DISPLAY INVISIBLE (-6575 -3225);
FORCEPROP 2 LAST ROOM BMC
J 0
(-6875 -3225);
DISPLAY 1.361702 (-6875 -3225);
PAINT ORANGE (-6875 -3225);
DISPLAY INVISIBLE (-6875 -3225);
FORCEPROP 2 LAST BOM_COST SM_CONTROLLER
J 0
(-6175 -3250);
PAINT MONO (-6175 -3250);
DISPLAY INVISIBLE (-6175 -3250);
FORCEADD OFFPAGE..1
(-6625 -3450);
FORCEPROP 2 LAST $XR0 21 
J 0
(-6846 -3450);
DISPLAY 0.638298 (-6846 -3450);
PAINT MONO (-6846 -3450);
FORCEPROP 2 LAST $XR1 118 
J 0
(-6966 -3450);
DISPLAY 0.638298 (-6966 -3450);
PAINT MONO (-6966 -3450);
FORCEPROP 2 LAST $XR2 190 
J 0
(-7086 -3450);
DISPLAY 0.638298 (-7086 -3450);
PAINT MONO (-7086 -3450);
FORCEPROP 1 LAST COMMENT_BODY TRUE
J 0
(-6500 -3550);
DISPLAY 0.872340 (-6500 -3550);
PAINT GREEN (-6500 -3550);
DISPLAY INVISIBLE (-6500 -3550);
FORCEPROP 1 LAST OFFPAGE TRUE
J 0
(-6300 -3575);
DISPLAY 0.872340 (-6300 -3575);
PAINT GREEN (-6300 -3575);
DISPLAY INVISIBLE (-6300 -3575);
FORCEPROP 2 LAST BOM_COST SM_CONTROLLER
J 0
(-6175 -3400);
PAINT MONO (-6175 -3400);
DISPLAY INVISIBLE (-6175 -3400);
FORCEPROP 2 LAST ROOM BMC
J 0
(-6875 -3375);
DISPLAY 1.361702 (-6875 -3375);
PAINT ORANGE (-6875 -3375);
DISPLAY INVISIBLE (-6875 -3375);
FORCEPROP 2 LAST PATH I45
J 0
(-6575 -3375);
DISPLAY 1.021277 (-6575 -3375);
PAINT ORANGE (-6575 -3375);
DISPLAY INVISIBLE (-6575 -3375);
FORCEPROP 2 LAST CDS_LIB mstr_standard
J 0
(-6625 -3450);
PAINT MONO (-6625 -3450);
DISPLAY INVISIBLE (-6625 -3450);
FORCEADD OFFPAGE..5
(-6650 -3550);
FORCEPROP 2 LAST $XR1 133 
J 0
(-7055 -3550);
DISPLAY 0.638298 (-7055 -3550);
PAINT MONO (-7055 -3550);
FORCEPROP 2 LAST $XR0 120 
J 0
(-6935 -3550);
DISPLAY 0.638298 (-6935 -3550);
PAINT MONO (-6935 -3550);
FORCEPROP 2 LAST $XR2 119 
J 0
(-7175 -3550);
DISPLAY 0.638298 (-7175 -3550);
PAINT MONO (-7175 -3550);
FORCEPROP 1 LAST COMMENT_BODY TRUE
J 0
(-6550 -3625);
DISPLAY 0.872340 (-6550 -3625);
PAINT GREEN (-6550 -3625);
DISPLAY INVISIBLE (-6550 -3625);
FORCEPROP 1 LAST OFFPAGE TRUE
J 0
(-6325 -3675);
DISPLAY 0.872340 (-6325 -3675);
PAINT GREEN (-6325 -3675);
DISPLAY INVISIBLE (-6325 -3675);
FORCEPROP 2 LAST PATH I47
J 0
(-6925 -3500);
DISPLAY 1.021277 (-6925 -3500);
PAINT ORANGE (-6925 -3500);
DISPLAY INVISIBLE (-6925 -3500);
FORCEPROP 2 LAST CDS_LIB mstr_standard
J 0
(-6650 -3550);
PAINT MONO (-6650 -3550);
DISPLAY INVISIBLE (-6650 -3550);
FORCEADD OFFPAGE..1
(-6625 -3600);
FORCEPROP 2 LAST $XR2 118 
J 0
(-7147 -3600);
DISPLAY 0.638298 (-7147 -3600);
PAINT MONO (-7147 -3600);
FORCEPROP 2 LAST $XR1 191 
J 0
(-7027 -3600);
DISPLAY 0.638298 (-7027 -3600);
PAINT MONO (-7027 -3600);
FORCEPROP 2 LAST $XR0 133 
J 0
(-6907 -3600);
DISPLAY 0.638298 (-6907 -3600);
PAINT MONO (-6907 -3600);
FORCEPROP 1 LAST COMMENT_BODY TRUE
J 0
(-6500 -3700);
DISPLAY 0.872340 (-6500 -3700);
PAINT GREEN (-6500 -3700);
DISPLAY INVISIBLE (-6500 -3700);
FORCEPROP 1 LAST OFFPAGE TRUE
J 0
(-6300 -3725);
DISPLAY 0.872340 (-6300 -3725);
PAINT GREEN (-6300 -3725);
DISPLAY INVISIBLE (-6300 -3725);
FORCEPROP 2 LAST PATH I48
J 0
(-6900 -3550);
DISPLAY 1.021277 (-6900 -3550);
PAINT ORANGE (-6900 -3550);
DISPLAY INVISIBLE (-6900 -3550);
FORCEPROP 2 LAST CDS_LIB mstr_standard
J 0
(-6625 -3600);
PAINT MONO (-6625 -3600);
DISPLAY INVISIBLE (-6625 -3600);
FORCEPROP 2 LAST ROOM BMC
J 0
(-6875 -3525);
DISPLAY 1.361702 (-6875 -3525);
PAINT ORANGE (-6875 -3525);
DISPLAY INVISIBLE (-6875 -3525);
FORCEPROP 2 LAST BOM_COST SM_CONTROLLER
J 0
(-6175 -3550);
PAINT MONO (-6175 -3550);
DISPLAY INVISIBLE (-6175 -3550);
FORCEADD OFFPAGE..1
(-6625 -3650);
FORCEPROP 2 LAST $XR2 119 
J 0
(-7087 -3650);
DISPLAY 0.638298 (-7087 -3650);
PAINT MONO (-7087 -3650);
FORCEPROP 2 LAST $XR1 94 
J 0
(-6967 -3650);
DISPLAY 0.638298 (-6967 -3650);
PAINT MONO (-6967 -3650);
FORCEPROP 2 LAST $XR0 223 
J 0
(-6877 -3650);
DISPLAY 0.638298 (-6877 -3650);
PAINT MONO (-6877 -3650);
FORCEPROP 1 LAST COMMENT_BODY TRUE
J 0
(-6500 -3750);
DISPLAY 0.872340 (-6500 -3750);
PAINT GREEN (-6500 -3750);
DISPLAY INVISIBLE (-6500 -3750);
FORCEPROP 1 LAST OFFPAGE TRUE
J 0
(-6300 -3775);
DISPLAY 0.872340 (-6300 -3775);
PAINT GREEN (-6300 -3775);
DISPLAY INVISIBLE (-6300 -3775);
FORCEPROP 2 LAST ROOM BMC
J 0
(-6875 -3575);
DISPLAY 1.361702 (-6875 -3575);
PAINT ORANGE (-6875 -3575);
DISPLAY INVISIBLE (-6875 -3575);
FORCEPROP 2 LAST BOM_COST SM_CONTROLLER
J 0
(-6175 -3600);
PAINT MONO (-6175 -3600);
DISPLAY INVISIBLE (-6175 -3600);
FORCEPROP 2 LAST CDS_LIB mstr_standard
J 0
(-6625 -3650);
PAINT ORANGE (-6625 -3650);
DISPLAY INVISIBLE (-6625 -3650);
FORCEPROP 2 LAST PATH I49
J 0
(-6875 -3600);
DISPLAY 1.021277 (-6875 -3600);
PAINT ORANGE (-6875 -3600);
DISPLAY INVISIBLE (-6875 -3600);
FORCEADD OFFPAGE..5
(-6625 -1750);
FORCEPROP 2 LAST $XR0 159 
J 0
(-6910 -1750);
DISPLAY 0.638298 (-6910 -1750);
PAINT MONO (-6910 -1750);
FORCEPROP 1 LAST COMMENT_BODY TRUE
J 0
(-6525 -1825);
DISPLAY 0.872340 (-6525 -1825);
PAINT GREEN (-6525 -1825);
DISPLAY INVISIBLE (-6525 -1825);
FORCEPROP 1 LAST OFFPAGE TRUE
J 0
(-6300 -1875);
DISPLAY 0.872340 (-6300 -1875);
PAINT GREEN (-6300 -1875);
DISPLAY INVISIBLE (-6300 -1875);
FORCEPROP 2 LAST CDS_LIB mstr_standard
J 0
(-6625 -1750);
PAINT MONO (-6625 -1750);
DISPLAY INVISIBLE (-6625 -1750);
FORCEPROP 2 LAST PATH I5
J 0
(-6575 -1675);
DISPLAY 1.021277 (-6575 -1675);
PAINT ORANGE (-6575 -1675);
DISPLAY INVISIBLE (-6575 -1675);
FORCEADD OFFPAGE..4
(-1950 -1900);
FORCEPROP 2 LAST $XR0 92 
J 0
(-1764 -1900);
DISPLAY 0.638298 (-1764 -1900);
PAINT MONO (-1764 -1900);
FORCEPROP 2 LAST $XR1 120 
J 0
(-1674 -1900);
DISPLAY 0.638298 (-1674 -1900);
PAINT MONO (-1674 -1900);
FORCEPROP 1 LAST COMMENT_BODY TRUE
J 0
(-1975 -2000);
DISPLAY 0.872340 (-1975 -2000);
PAINT GREEN (-1975 -2000);
DISPLAY INVISIBLE (-1975 -2000);
FORCEPROP 1 LAST OFFPAGE TRUE
J 0
(-1625 -2025);
DISPLAY 0.872340 (-1625 -2025);
PAINT GREEN (-1625 -2025);
DISPLAY INVISIBLE (-1625 -2025);
FORCEPROP 2 LAST CDS_LIB mstr_standard
J 0
(-1950 -1900);
PAINT MONO (-1950 -1900);
DISPLAY INVISIBLE (-1950 -1900);
FORCEPROP 2 LAST PATH I50
J 0
(-1650 -1850);
DISPLAY 1.021277 (-1650 -1850);
PAINT ORANGE (-1650 -1850);
DISPLAY INVISIBLE (-1650 -1850);
FORCEADD OFFPAGE..4
(-1950 -1850);
FORCEPROP 2 LAST $XR1 190 
J 0
(-1674 -1850);
DISPLAY 0.638298 (-1674 -1850);
PAINT MONO (-1674 -1850);
FORCEPROP 2 LAST $XR0 92 
J 0
(-1764 -1850);
DISPLAY 0.638298 (-1764 -1850);
PAINT MONO (-1764 -1850);
FORCEPROP 1 LAST COMMENT_BODY TRUE
J 0
(-1975 -1950);
DISPLAY 0.872340 (-1975 -1950);
PAINT GREEN (-1975 -1950);
DISPLAY INVISIBLE (-1975 -1950);
FORCEPROP 1 LAST OFFPAGE TRUE
J 0
(-1625 -1975);
DISPLAY 0.872340 (-1625 -1975);
PAINT GREEN (-1625 -1975);
DISPLAY INVISIBLE (-1625 -1975);
FORCEPROP 2 LAST PATH I51
J 0
(-1650 -1800);
DISPLAY 1.021277 (-1650 -1800);
PAINT ORANGE (-1650 -1800);
DISPLAY INVISIBLE (-1650 -1800);
FORCEPROP 2 LAST CDS_LIB mstr_standard
J 0
(-1950 -1850);
PAINT ORANGE (-1950 -1850);
DISPLAY INVISIBLE (-1950 -1850);
FORCEADD OFFPAGE..4
(-1950 -1750);
FORCEPROP 2 LAST $XR1 120 
J 0
(-1644 -1750);
DISPLAY 0.638298 (-1644 -1750);
PAINT MONO (-1644 -1750);
FORCEPROP 2 LAST $XR0 134 
J 0
(-1764 -1750);
DISPLAY 0.638298 (-1764 -1750);
PAINT MONO (-1764 -1750);
FORCEPROP 1 LAST COMMENT_BODY TRUE
J 0
(-1975 -1850);
DISPLAY 0.872340 (-1975 -1850);
PAINT GREEN (-1975 -1850);
DISPLAY INVISIBLE (-1975 -1850);
FORCEPROP 1 LAST OFFPAGE TRUE
J 0
(-1625 -1875);
DISPLAY 0.872340 (-1625 -1875);
PAINT GREEN (-1625 -1875);
DISPLAY INVISIBLE (-1625 -1875);
FORCEPROP 2 LAST PATH I52
J 0
(-1625 -1700);
DISPLAY 1.021277 (-1625 -1700);
PAINT ORANGE (-1625 -1700);
DISPLAY INVISIBLE (-1625 -1700);
FORCEPROP 2 LAST CDS_LIB mstr_standard
J 0
(-1950 -1750);
PAINT ORANGE (-1950 -1750);
DISPLAY INVISIBLE (-1950 -1750);
FORCEADD OFFPAGE..2
(-675 -2150);
FORCEPROP 2 LAST $XR0 190 
J 0
(-486 -2150);
DISPLAY 0.638298 (-486 -2150);
PAINT MONO (-486 -2150);
FORCEPROP 1 LAST COMMENT_BODY TRUE
J 0
(-720 -2245);
DISPLAY 0.872340 (-720 -2245);
PAINT GREEN (-720 -2245);
DISPLAY INVISIBLE (-720 -2245);
FORCEPROP 1 LAST OFFPAGE TRUE
J 0
(-350 -2275);
DISPLAY 0.872340 (-350 -2275);
PAINT GREEN (-350 -2275);
DISPLAY INVISIBLE (-350 -2275);
FORCEPROP 2 LAST CDS_LIB mstr_standard
J 0
(-675 -2150);
PAINT MONO (-675 -2150);
DISPLAY INVISIBLE (-675 -2150);
FORCEPROP 2 LAST PATH I53
J 0
(-475 -2100);
DISPLAY 1.021277 (-475 -2100);
PAINT ORANGE (-475 -2100);
DISPLAY INVISIBLE (-475 -2100);
FORCEADD OFFPAGE..2
(-675 -2050);
FORCEPROP 2 LAST $XR0 190 
J 0
(-486 -2050);
DISPLAY 0.638298 (-486 -2050);
PAINT MONO (-486 -2050);
FORCEPROP 1 LAST COMMENT_BODY TRUE
J 0
(-720 -2145);
DISPLAY 0.872340 (-720 -2145);
PAINT GREEN (-720 -2145);
DISPLAY INVISIBLE (-720 -2145);
FORCEPROP 1 LAST OFFPAGE TRUE
J 0
(-350 -2175);
DISPLAY 0.872340 (-350 -2175);
PAINT GREEN (-350 -2175);
DISPLAY INVISIBLE (-350 -2175);
FORCEPROP 2 LAST CDS_LIB mstr_standard
J 0
(-675 -2050);
PAINT MONO (-675 -2050);
DISPLAY INVISIBLE (-675 -2050);
FORCEPROP 2 LAST PATH I54
J 0
(-475 -2000);
DISPLAY 1.021277 (-475 -2000);
PAINT ORANGE (-475 -2000);
DISPLAY INVISIBLE (-475 -2000);
FORCEADD OFFPAGE..2
(-675 -2200);
FORCEPROP 2 LAST $XR0 190 
J 0
(-486 -2200);
DISPLAY 0.638298 (-486 -2200);
PAINT MONO (-486 -2200);
FORCEPROP 1 LAST COMMENT_BODY TRUE
J 0
(-720 -2295);
DISPLAY 0.872340 (-720 -2295);
PAINT GREEN (-720 -2295);
DISPLAY INVISIBLE (-720 -2295);
FORCEPROP 1 LAST OFFPAGE TRUE
J 0
(-350 -2325);
DISPLAY 0.872340 (-350 -2325);
PAINT GREEN (-350 -2325);
DISPLAY INVISIBLE (-350 -2325);
FORCEPROP 2 LAST CDS_LIB mstr_standard
J 0
(-675 -2200);
PAINT MONO (-675 -2200);
DISPLAY INVISIBLE (-675 -2200);
FORCEPROP 2 LAST PATH I55
J 0
(-475 -2150);
DISPLAY 1.021277 (-475 -2150);
PAINT ORANGE (-475 -2150);
DISPLAY INVISIBLE (-475 -2150);
FORCEADD OFFPAGE..4
(-1950 -2000);
FORCEPROP 2 LAST $XR0 191 
J 0
(-1764 -2000);
DISPLAY 0.638298 (-1764 -2000);
PAINT MONO (-1764 -2000);
FORCEPROP 1 LAST COMMENT_BODY TRUE
J 0
(-1975 -2100);
DISPLAY 0.872340 (-1975 -2100);
PAINT GREEN (-1975 -2100);
DISPLAY INVISIBLE (-1975 -2100);
FORCEPROP 1 LAST OFFPAGE TRUE
J 0
(-1625 -2125);
DISPLAY 0.872340 (-1625 -2125);
PAINT GREEN (-1625 -2125);
DISPLAY INVISIBLE (-1625 -2125);
FORCEPROP 2 LAST PATH I56
J 0
(-1750 -1950);
DISPLAY 1.021277 (-1750 -1950);
PAINT ORANGE (-1750 -1950);
DISPLAY INVISIBLE (-1750 -1950);
FORCEPROP 2 LAST CDS_LIB mstr_standard
J 0
(-1950 -2000);
PAINT MONO (-1950 -2000);
DISPLAY INVISIBLE (-1950 -2000);
FORCEADD RES..1
(-1500 -2200);
FORCEPROP 1 LAST TOLERANCE 5.0%
J 0
(-1450 -2250);
DISPLAY 0.617021 (-1450 -2250);
PAINT SKYBLUE (-1450 -2250);
FORCEPROP 1 LAST WATTAGE 1/16W
J 2
(-1200 -2250);
DISPLAY 0.617021 (-1200 -2250);
PAINT SKYBLUE (-1200 -2250);
FORCEPROP 1 LAST LOCATION R1U14
J 0
(-1750 -2250);
DISPLAY 0.617021 (-1750 -2250);
PAINT AQUA (-1750 -2250);
FORCEPROP 1 LAST PART_NUMBER G21497-048
J 0
(-1175 -2250);
DISPLAY 0.617021 (-1175 -2250);
PAINT BLUE (-1175 -2250);
FORCEPROP 1 LAST VALUE 51
J 2
(-1525 -2250);
DISPLAY 0.617021 (-1525 -2250);
PAINT SKYBLUE (-1525 -2250);
FORCEPROP 1 LAST PATH I57
J 0
(-1550 -2050);
DISPLAY 0.978723 (-1550 -2050);
PAINT WHITE (-1550 -2050);
DISPLAY INVISIBLE (-1550 -2050);
FORCEPROP 2 LAST CDS_LOCATION R1U14
J 0
(-1675 -2250);
DISPLAY 0.617021 (-1675 -2250);
PAINT AQUA (-1675 -2250);
DISPLAY INVISIBLE (-1675 -2250);
FORCEPROP 1 LAST MATERIAL CHIP
J 0
(-1500 -2350);
DISPLAY 0.617021 (-1500 -2350);
PAINT SKYBLUE (-1500 -2350);
DISPLAY INVISIBLE (-1500 -2350);
FORCEPROP 1 LASTPIN (-1600 -2200) $PN 1
J 0
(-1588 -2188);
DISPLAY 0.787234 (-1588 -2188);
PAINT ORANGE (-1588 -2188);
DISPLAY INVISIBLE (-1588 -2188);
FORCEPROP 2 LAST $SEC 1
J 0
(-1550 -2000);
PAINT MONO (-1550 -2000);
DISPLAY INVISIBLE (-1550 -2000);
FORCEPROP 2 LAST CDS_SEC 1
J 0
(-1550 -2000);
PAINT MONO (-1550 -2000);
DISPLAY INVISIBLE (-1550 -2000);
FORCEPROP 2 LAST CDS_LIB mstr_discrete
J 0
(-1500 -2200);
PAINT MONO (-1500 -2200);
DISPLAY INVISIBLE (-1500 -2200);
FORCEPROP 1 LASTPIN (-1400 -2200) $PN 2
J 0
(-1438 -2188);
DISPLAY 0.787234 (-1438 -2188);
PAINT ORANGE (-1438 -2188);
DISPLAY INVISIBLE (-1438 -2188);
FORCEPROP 2 LAST ROOM BMC
J 0
(-1175 -2200);
PAINT MONO (-1175 -2200);
DISPLAY INVISIBLE (-1175 -2200);
FORCEPROP 1 LAST PACK_TYPE 0402
J 0
(-1250 -2350);
DISPLAY 0.617021 (-1250 -2350);
PAINT SKYBLUE (-1250 -2350);
DISPLAY INVISIBLE (-1250 -2350);
FORCEADD RES..1
(-1475 -2050);
FORCEPROP 1 LAST PART_NUMBER G21497-048
J 0
(-1375 -2025);
DISPLAY 0.617021 (-1375 -2025);
PAINT BLUE (-1375 -2025);
FORCEPROP 1 LAST VALUE 51
J 2
(-1425 -2000);
DISPLAY 0.617021 (-1425 -2000);
PAINT SKYBLUE (-1425 -2000);
FORCEPROP 1 LAST LOCATION R1U13
J 0
(-1625 -2000);
DISPLAY 0.617021 (-1625 -2000);
PAINT AQUA (-1625 -2000);
FORCEPROP 1 LAST WATTAGE 1/16W
J 2
(-1175 -2100);
DISPLAY 0.617021 (-1175 -2100);
PAINT SKYBLUE (-1175 -2100);
FORCEPROP 1 LAST TOLERANCE 5.0%
J 0
(-1425 -2100);
DISPLAY 0.617021 (-1425 -2100);
PAINT SKYBLUE (-1425 -2100);
FORCEPROP 2 LAST CDS_SEC 1
J 0
(-1525 -1850);
PAINT MONO (-1525 -1850);
DISPLAY INVISIBLE (-1525 -1850);
FORCEPROP 2 LAST $SEC 1
J 0
(-1525 -1850);
PAINT MONO (-1525 -1850);
DISPLAY INVISIBLE (-1525 -1850);
FORCEPROP 1 LAST PACK_TYPE 0402
J 0
(-1225 -2200);
DISPLAY 0.617021 (-1225 -2200);
PAINT SKYBLUE (-1225 -2200);
DISPLAY INVISIBLE (-1225 -2200);
FORCEPROP 2 LAST ROOM BMC
J 0
(-1150 -2050);
PAINT MONO (-1150 -2050);
DISPLAY INVISIBLE (-1150 -2050);
FORCEPROP 1 LASTPIN (-1375 -2050) $PN 2
J 0
(-1413 -2038);
DISPLAY 0.787234 (-1413 -2038);
PAINT ORANGE (-1413 -2038);
DISPLAY INVISIBLE (-1413 -2038);
FORCEPROP 2 LAST CDS_LIB mstr_discrete
J 0
(-1475 -2050);
PAINT MONO (-1475 -2050);
DISPLAY INVISIBLE (-1475 -2050);
FORCEPROP 1 LAST MATERIAL CHIP
J 0
(-1475 -2200);
DISPLAY 0.617021 (-1475 -2200);
PAINT SKYBLUE (-1475 -2200);
DISPLAY INVISIBLE (-1475 -2200);
FORCEPROP 1 LASTPIN (-1575 -2050) $PN 1
J 0
(-1563 -2038);
DISPLAY 0.787234 (-1563 -2038);
PAINT ORANGE (-1563 -2038);
DISPLAY INVISIBLE (-1563 -2038);
FORCEPROP 2 LAST CDS_LOCATION R1U13
J 0
(-1650 -2100);
DISPLAY 0.617021 (-1650 -2100);
PAINT AQUA (-1650 -2100);
DISPLAY INVISIBLE (-1650 -2100);
FORCEPROP 1 LAST PATH I58
J 0
(-1525 -1900);
DISPLAY 0.978723 (-1525 -1900);
PAINT WHITE (-1525 -1900);
DISPLAY INVISIBLE (-1525 -1900);
FORCEADD RES..1
(-1475 -2150);
FORCEPROP 1 LAST VALUE 51
J 2
(-1500 -2125);
DISPLAY 0.617021 (-1500 -2125);
PAINT SKYBLUE (-1500 -2125);
FORCEPROP 1 LAST LOCATION R1U12
J 0
(-1775 -2125);
DISPLAY 0.617021 (-1775 -2125);
PAINT AQUA (-1775 -2125);
FORCEPROP 1 LAST TOLERANCE 5.0%
J 0
(-1625 -2175);
DISPLAY 0.617021 (-1625 -2175);
PAINT SKYBLUE (-1625 -2175);
FORCEPROP 1 LAST PART_NUMBER G21497-048
J 0
(-1325 -2125);
DISPLAY 0.617021 (-1325 -2125);
PAINT BLUE (-1325 -2125);
FORCEPROP 1 LAST WATTAGE 1/16W
J 2
(-1300 -2175);
DISPLAY 0.617021 (-1300 -2175);
PAINT SKYBLUE (-1300 -2175);
FORCEPROP 2 LAST ROOM BMC
J 0
(-1150 -2150);
PAINT MONO (-1150 -2150);
DISPLAY INVISIBLE (-1150 -2150);
FORCEPROP 2 LAST CDS_SEC 1
J 0
(-1525 -1950);
PAINT MONO (-1525 -1950);
DISPLAY INVISIBLE (-1525 -1950);
FORCEPROP 2 LAST $SEC 1
J 0
(-1525 -1950);
PAINT MONO (-1525 -1950);
DISPLAY INVISIBLE (-1525 -1950);
FORCEPROP 1 LASTPIN (-1375 -2150) $PN 2
J 0
(-1413 -2138);
DISPLAY 0.787234 (-1413 -2138);
PAINT ORANGE (-1413 -2138);
DISPLAY INVISIBLE (-1413 -2138);
FORCEPROP 1 LAST PACK_TYPE 0402
J 0
(-1225 -2300);
DISPLAY 0.617021 (-1225 -2300);
PAINT SKYBLUE (-1225 -2300);
DISPLAY INVISIBLE (-1225 -2300);
FORCEPROP 2 LAST CDS_LIB mstr_discrete
J 0
(-1475 -2150);
PAINT MONO (-1475 -2150);
DISPLAY INVISIBLE (-1475 -2150);
FORCEPROP 2 LAST CDS_LOCATION R1U12
J 0
(-1500 -2100);
DISPLAY 0.617021 (-1500 -2100);
PAINT AQUA (-1500 -2100);
DISPLAY INVISIBLE (-1500 -2100);
FORCEPROP 1 LASTPIN (-1575 -2150) $PN 1
J 0
(-1563 -2138);
DISPLAY 0.787234 (-1563 -2138);
PAINT ORANGE (-1563 -2138);
DISPLAY INVISIBLE (-1563 -2138);
FORCEPROP 1 LAST MATERIAL CHIP
J 0
(-1475 -2300);
DISPLAY 0.617021 (-1475 -2300);
PAINT SKYBLUE (-1475 -2300);
DISPLAY INVISIBLE (-1475 -2300);
FORCEPROP 1 LAST PATH I59
J 0
(-1525 -2000);
DISPLAY 0.978723 (-1525 -2000);
PAINT WHITE (-1525 -2000);
DISPLAY INVISIBLE (-1525 -2000);
FORCEADD OFFPAGE..4
(-1700 -2300);
FORCEPROP 2 LAST $XR0 218 
J 0
(-1514 -2300);
DISPLAY 0.638298 (-1514 -2300);
PAINT MONO (-1514 -2300);
FORCEPROP 2 LAST $XR2 119 
J 0
(-1304 -2300);
DISPLAY 0.638298 (-1304 -2300);
PAINT MONO (-1304 -2300);
FORCEPROP 2 LAST $XR1 94 
J 0
(-1394 -2300);
DISPLAY 0.638298 (-1394 -2300);
PAINT MONO (-1394 -2300);
FORCEPROP 1 LAST COMMENT_BODY TRUE
J 0
(-1725 -2400);
DISPLAY 0.872340 (-1725 -2400);
PAINT GREEN (-1725 -2400);
DISPLAY INVISIBLE (-1725 -2400);
FORCEPROP 1 LAST OFFPAGE TRUE
J 0
(-1375 -2425);
DISPLAY 0.872340 (-1375 -2425);
PAINT GREEN (-1375 -2425);
DISPLAY INVISIBLE (-1375 -2425);
FORCEPROP 2 LAST PATH I60
J 0
(-1300 -2250);
DISPLAY 1.021277 (-1300 -2250);
PAINT ORANGE (-1300 -2250);
DISPLAY INVISIBLE (-1300 -2250);
FORCEPROP 2 LAST CDS_LIB mstr_standard
J 0
(-1700 -2300);
PAINT MONO (-1700 -2300);
DISPLAY INVISIBLE (-1700 -2300);
FORCEADD OFFPAGE..4
(-1725 -2900);
FORCEPROP 2 LAST $XR1 189 
J 0
(-1419 -2900);
DISPLAY 0.638298 (-1419 -2900);
PAINT MONO (-1419 -2900);
FORCEPROP 2 LAST $XR0 151 
J 0
(-1539 -2900);
DISPLAY 0.638298 (-1539 -2900);
PAINT MONO (-1539 -2900);
FORCEPROP 2 LAST CDS_LIB mstr_standard
J 0
(-1725 -2900);
PAINT MONO (-1725 -2900);
DISPLAY INVISIBLE (-1725 -2900);
FORCEPROP 2 LAST PATH I66
J 0
(-1550 -2825);
DISPLAY 1.021277 (-1550 -2825);
PAINT ORANGE (-1550 -2825);
DISPLAY INVISIBLE (-1550 -2825);
FORCEPROP 1 LAST OFFPAGE TRUE
J 0
(-1400 -3025);
DISPLAY 0.872340 (-1400 -3025);
PAINT GREEN (-1400 -3025);
DISPLAY INVISIBLE (-1400 -3025);
FORCEPROP 1 LAST COMMENT_BODY TRUE
J 0
(-1750 -3000);
DISPLAY 0.872340 (-1750 -3000);
PAINT GREEN (-1750 -3000);
DISPLAY INVISIBLE (-1750 -3000);
FORCEADD OFFPAGE..2
(-1700 -3100);
FORCEPROP 2 LAST $XR0 189 
J 0
(-1511 -3100);
DISPLAY 0.638298 (-1511 -3100);
PAINT MONO (-1511 -3100);
FORCEPROP 2 LAST PATH I67
J 0
(-1525 -3025);
DISPLAY 1.021277 (-1525 -3025);
PAINT ORANGE (-1525 -3025);
DISPLAY INVISIBLE (-1525 -3025);
FORCEPROP 2 LAST CDS_LIB mstr_standard
J 0
(-1700 -3100);
PAINT MONO (-1700 -3100);
DISPLAY INVISIBLE (-1700 -3100);
FORCEPROP 1 LAST OFFPAGE TRUE
J 0
(-1375 -3225);
DISPLAY 0.872340 (-1375 -3225);
PAINT GREEN (-1375 -3225);
DISPLAY INVISIBLE (-1375 -3225);
FORCEPROP 1 LAST COMMENT_BODY TRUE
J 0
(-1745 -3195);
DISPLAY 0.872340 (-1745 -3195);
PAINT GREEN (-1745 -3195);
DISPLAY INVISIBLE (-1745 -3195);
FORCEADD OFFPAGE..4
(-1725 -2950);
FORCEPROP 2 LAST $XR0 189 
J 0
(-1539 -2950);
DISPLAY 0.638298 (-1539 -2950);
PAINT MONO (-1539 -2950);
FORCEPROP 2 LAST PATH I68
J 0
(-1550 -2875);
DISPLAY 1.021277 (-1550 -2875);
PAINT ORANGE (-1550 -2875);
DISPLAY INVISIBLE (-1550 -2875);
FORCEPROP 2 LAST CDS_LIB mstr_standard
J 0
(-1725 -2950);
PAINT MONO (-1725 -2950);
DISPLAY INVISIBLE (-1725 -2950);
FORCEPROP 1 LAST OFFPAGE TRUE
J 0
(-1400 -3075);
DISPLAY 0.872340 (-1400 -3075);
PAINT GREEN (-1400 -3075);
DISPLAY INVISIBLE (-1400 -3075);
FORCEPROP 1 LAST COMMENT_BODY TRUE
J 0
(-1750 -3050);
DISPLAY 0.872340 (-1750 -3050);
PAINT GREEN (-1750 -3050);
DISPLAY INVISIBLE (-1750 -3050);
FORCEADD OFFPAGE..4
(-1725 -3000);
FORCEPROP 2 LAST $XR0 189 
J 0
(-1539 -3000);
DISPLAY 0.638298 (-1539 -3000);
PAINT MONO (-1539 -3000);
FORCEPROP 2 LAST PATH I69
J 0
(-1550 -2925);
DISPLAY 1.021277 (-1550 -2925);
PAINT ORANGE (-1550 -2925);
DISPLAY INVISIBLE (-1550 -2925);
FORCEPROP 2 LAST CDS_LIB mstr_standard
J 0
(-1725 -3000);
PAINT MONO (-1725 -3000);
DISPLAY INVISIBLE (-1725 -3000);
FORCEPROP 1 LAST OFFPAGE TRUE
J 0
(-1400 -3125);
DISPLAY 0.872340 (-1400 -3125);
PAINT GREEN (-1400 -3125);
DISPLAY INVISIBLE (-1400 -3125);
FORCEPROP 1 LAST COMMENT_BODY TRUE
J 0
(-1750 -3100);
DISPLAY 0.872340 (-1750 -3100);
PAINT GREEN (-1750 -3100);
DISPLAY INVISIBLE (-1750 -3100);
FORCEADD OFFPAGE..4
(-1725 -3050);
FORCEPROP 2 LAST $XR0 189 
J 0
(-1539 -3050);
DISPLAY 0.638298 (-1539 -3050);
PAINT MONO (-1539 -3050);
FORCEPROP 2 LAST PATH I70
J 0
(-1550 -2975);
DISPLAY 1.021277 (-1550 -2975);
PAINT ORANGE (-1550 -2975);
DISPLAY INVISIBLE (-1550 -2975);
FORCEPROP 2 LAST CDS_LIB mstr_standard
J 0
(-1725 -3050);
PAINT MONO (-1725 -3050);
DISPLAY INVISIBLE (-1725 -3050);
FORCEPROP 1 LAST OFFPAGE TRUE
J 0
(-1400 -3175);
DISPLAY 0.872340 (-1400 -3175);
PAINT GREEN (-1400 -3175);
DISPLAY INVISIBLE (-1400 -3175);
FORCEPROP 1 LAST COMMENT_BODY TRUE
J 0
(-1750 -3150);
DISPLAY 0.872340 (-1750 -3150);
PAINT GREEN (-1750 -3150);
DISPLAY INVISIBLE (-1750 -3150);
FORCEADD GND..1
(-1600 -3850);
FORCEPROP 3 LASTPIN (-1600 -3800) SIG_NAME GND\g
J 0
(-1590 -3790);
DISPLAY 0.659574 (-1590 -3790);
PAINT MONO (-1590 -3790);
DISPLAY INVISIBLE (-1590 -3790);
FORCEPROP 2 LAST CDS_LIB mstr_symbols
J 0
(-1647 -3803);
PAINT ORANGE (-1647 -3803);
DISPLAY INVISIBLE (-1647 -3803);
FORCEPROP 1 LAST VOLTAGE 0.0V
J 0
(-1661 -3877);
DISPLAY 0.340426 (-1661 -3877);
PAINT SKYBLUE (-1661 -3877);
DISPLAY INVISIBLE (-1661 -3877);
FORCEPROP 1 LAST SIZE 1B
J 0
(-1566 -3859);
DISPLAY 0.872340 (-1566 -3859);
PAINT AQUA (-1566 -3859);
DISPLAY INVISIBLE (-1566 -3859);
FORCEPROP 1 LAST PATH I72
J 0
(-1566 -3809);
DISPLAY 0.872340 (-1566 -3809);
PAINT AQUA (-1566 -3809);
DISPLAY INVISIBLE (-1566 -3809);
FORCEPROP 1 LAST BODY_TYPE PLUMBING
J 0
(-1661 -3877);
DISPLAY 0.340426 (-1661 -3877);
PAINT GREEN (-1661 -3877);
DISPLAY INVISIBLE (-1661 -3877);
FORCEPROP 1 LAST HDL_POWER GND
J 0
(-1641 -3659);
DISPLAY 0.872340 (-1641 -3659);
PAINT GREEN (-1641 -3659);
DISPLAY INVISIBLE (-1641 -3659);
FORCEADD RES..2
(-1600 -3550);
FORCEPROP 1 LAST LOCATION R25W58
J 0
(-1555 -3425);
DISPLAY 0.617021 (-1555 -3425);
PAINT AQUA (-1555 -3425);
FORCEPROP 1 LAST VALUE 2.7K
J 0
(-1555 -3475);
DISPLAY 0.617021 (-1555 -3475);
PAINT SKYBLUE (-1555 -3475);
FORCEPROP 1 LAST TOLERANCE 1%
J 0
(-1555 -3525);
DISPLAY 0.617021 (-1555 -3525);
PAINT SKYBLUE (-1555 -3525);
FORCEPROP 1 LAST MATERIAL CHIP
J 0
(-1560 -3625);
DISPLAY 0.617021 (-1560 -3625);
PAINT SKYBLUE (-1560 -3625);
FORCEPROP 1 LAST WATTAGE 1/16W
J 0
(-1560 -3575);
DISPLAY 0.617021 (-1560 -3575);
PAINT SKYBLUE (-1560 -3575);
FORCEPROP 1 LAST PACK_TYPE 0402
J 0
(-1560 -3725);
DISPLAY 0.617021 (-1560 -3725);
PAINT SKYBLUE (-1560 -3725);
FORCEPROP 1 LAST PART_NUMBER G21796-344
J 0
(-1560 -3675);
DISPLAY 0.617021 (-1560 -3675);
PAINT BLUE (-1560 -3675);
FORCEPROP 1 LASTPIN (-1600 -3450) $PN 1
J 0
(-1595 -3488);
DISPLAY 0.617021 (-1595 -3488);
PAINT ORANGE (-1595 -3488);
FORCEPROP 1 LASTPIN (-1600 -3650) $PN 2
J 0
(-1595 -3640);
DISPLAY 0.617021 (-1595 -3640);
PAINT ORANGE (-1595 -3640);
FORCEPROP 1 LAST PATH I73
J 0
(-1550 -3375);
DISPLAY 0.978723 (-1550 -3375);
PAINT WHITE (-1550 -3375);
DISPLAY INVISIBLE (-1550 -3375);
FORCEPROP 0 LAST BOM_COST SM_CONTROLLER
J 0
(-1550 -3225);
DISPLAY 1.021277 (-1550 -3225);
PAINT ORANGE (-1550 -3225);
DISPLAY INVISIBLE (-1550 -3225);
FORCEPROP 0 LAST ROOM BMC
J 0
(-1550 -3325);
DISPLAY 0.617021 (-1550 -3325);
PAINT ORANGE (-1550 -3325);
DISPLAY INVISIBLE (-1550 -3325);
FORCEPROP 2 LAST SEC 1
J 0
(-1550 -3325);
DISPLAY 0.680851 (-1550 -3325);
PAINT MONO (-1550 -3325);
DISPLAY INVISIBLE (-1550 -3325);
FORCEPROP 2 LAST SEC_TYPE 0402
J 0
(-1550 -3325);
DISPLAY 1.021277 (-1550 -3325);
PAINT ORANGE (-1550 -3325);
DISPLAY INVISIBLE (-1550 -3325);
FORCEPROP 2 LAST CDS_LIB mstr_discrete
J 0
(-1600 -3550);
PAINT ORANGE (-1600 -3550);
DISPLAY INVISIBLE (-1600 -3550);
FORCEPROP 0 LAST CDS_SEC 1
J 0
(-1550 -3375);
PAINT MONO (-1550 -3375);
DISPLAY INVISIBLE (-1550 -3375);
FORCEPROP 2 LAST CDS_LOCATION R25W58
J 0
(-1555 -3425);
DISPLAY 0.617021 (-1555 -3425);
PAINT AQUA (-1555 -3425);
DISPLAY INVISIBLE (-1555 -3425);
FORCEADD OFFPAGE..1
(-6625 -3400);
FORCEPROP 2 LAST $XR0 157 
J 0
(-6877 -3400);
DISPLAY 0.638298 (-6877 -3400);
PAINT MONO (-6877 -3400);
FORCEPROP 2 LAST $XR1 181 
J 0
(-6997 -3400);
DISPLAY 0.638298 (-6997 -3400);
PAINT MONO (-6997 -3400);
FORCEPROP 2 LAST $XR3 190 
J 0
(-7237 -3400);
DISPLAY 0.638298 (-7237 -3400);
PAINT MONO (-7237 -3400);
FORCEPROP 2 LAST $XR2 120 
J 0
(-7117 -3400);
DISPLAY 0.638298 (-7117 -3400);
PAINT MONO (-7117 -3400);
FORCEPROP 1 LAST COMMENT_BODY TRUE
J 0
(-6500 -3500);
DISPLAY 0.872340 (-6500 -3500);
PAINT GREEN (-6500 -3500);
DISPLAY INVISIBLE (-6500 -3500);
FORCEPROP 1 LAST OFFPAGE TRUE
J 0
(-6300 -3525);
DISPLAY 0.872340 (-6300 -3525);
PAINT GREEN (-6300 -3525);
DISPLAY INVISIBLE (-6300 -3525);
FORCEPROP 2 LAST ROOM BMC
J 0
(-6875 -3325);
DISPLAY 1.361702 (-6875 -3325);
PAINT ORANGE (-6875 -3325);
DISPLAY INVISIBLE (-6875 -3325);
FORCEPROP 2 LAST BOM_COST SM_CONTROLLER
J 0
(-6175 -3350);
PAINT MONO (-6175 -3350);
DISPLAY INVISIBLE (-6175 -3350);
FORCEPROP 2 LAST PATH I74
J 0
(-6575 -3325);
DISPLAY 1.021277 (-6575 -3325);
PAINT ORANGE (-6575 -3325);
DISPLAY INVISIBLE (-6575 -3325);
FORCEPROP 2 LAST CDS_LIB mstr_standard
J 0
(-6625 -3400);
PAINT MONO (-6625 -3400);
DISPLAY INVISIBLE (-6625 -3400);
FORCEADD OFFPAGE..2
(-1675 -2500);
FORCEPROP 2 LAST $XR0 119 
J 0
(-1486 -2500);
DISPLAY 0.638298 (-1486 -2500);
PAINT MONO (-1486 -2500);
FORCEPROP 2 LAST $XR1 156 
J 0
(-1366 -2500);
DISPLAY 0.638298 (-1366 -2500);
PAINT MONO (-1366 -2500);
FORCEPROP 1 LAST COMMENT_BODY TRUE
J 0
(-1720 -2595);
DISPLAY 0.872340 (-1720 -2595);
PAINT GREEN (-1720 -2595);
DISPLAY INVISIBLE (-1720 -2595);
FORCEPROP 1 LAST OFFPAGE TRUE
J 0
(-1350 -2625);
DISPLAY 0.872340 (-1350 -2625);
PAINT GREEN (-1350 -2625);
DISPLAY INVISIBLE (-1350 -2625);
FORCEPROP 2 LAST PATH I75
J 0
(-1350 -2450);
DISPLAY 1.021277 (-1350 -2450);
PAINT ORANGE (-1350 -2450);
DISPLAY INVISIBLE (-1350 -2450);
FORCEPROP 2 LAST CDS_LIB mstr_standard
J 0
(-1675 -2500);
PAINT ORANGE (-1675 -2500);
DISPLAY INVISIBLE (-1675 -2500);
FORCEADD OFFPAGE..4
(-1700 -2450);
FORCEPROP 2 LAST $XR0 168 
J 0
(-1514 -2450);
DISPLAY 0.638298 (-1514 -2450);
PAINT MONO (-1514 -2450);
FORCEPROP 2 LAST $XR1 120 
J 0
(-1394 -2450);
DISPLAY 0.638298 (-1394 -2450);
PAINT MONO (-1394 -2450);
FORCEPROP 2 LAST $XR2 190 
J 0
(-1274 -2450);
DISPLAY 0.638298 (-1274 -2450);
PAINT MONO (-1274 -2450);
FORCEPROP 1 LAST COMMENT_BODY TRUE
J 0
(-1725 -2550);
DISPLAY 0.872340 (-1725 -2550);
PAINT GREEN (-1725 -2550);
DISPLAY INVISIBLE (-1725 -2550);
FORCEPROP 1 LAST OFFPAGE TRUE
J 0
(-1375 -2575);
DISPLAY 0.872340 (-1375 -2575);
PAINT GREEN (-1375 -2575);
DISPLAY INVISIBLE (-1375 -2575);
FORCEPROP 2 LAST CDS_LIB mstr_standard
J 0
(-1700 -2450);
PAINT MONO (-1700 -2450);
DISPLAY INVISIBLE (-1700 -2450);
FORCEPROP 2 LAST PATH I76
J 0
(-1525 -2375);
DISPLAY 1.021277 (-1525 -2375);
PAINT ORANGE (-1525 -2375);
DISPLAY INVISIBLE (-1525 -2375);
FORCEADD OFFPAGE..4
(-1700 -2350);
FORCEPROP 2 LAST $XR0 89 
J 0
(-1514 -2350);
DISPLAY 0.638298 (-1514 -2350);
PAINT MONO (-1514 -2350);
FORCEPROP 2 LAST $XR1 120 
J 0
(-1424 -2350);
DISPLAY 0.638298 (-1424 -2350);
PAINT MONO (-1424 -2350);
FORCEPROP 1 LAST COMMENT_BODY TRUE
J 0
(-1725 -2450);
DISPLAY 0.872340 (-1725 -2450);
PAINT GREEN (-1725 -2450);
DISPLAY INVISIBLE (-1725 -2450);
FORCEPROP 1 LAST OFFPAGE TRUE
J 0
(-1375 -2475);
DISPLAY 0.872340 (-1375 -2475);
PAINT GREEN (-1375 -2475);
DISPLAY INVISIBLE (-1375 -2475);
FORCEPROP 2 LAST CDS_LIB mstr_standard
J 0
(-1700 -2350);
PAINT MONO (-1700 -2350);
DISPLAY INVISIBLE (-1700 -2350);
FORCEPROP 2 LAST PATH I77
J 0
(-1525 -2275);
DISPLAY 1.021277 (-1525 -2275);
PAINT ORANGE (-1525 -2275);
DISPLAY INVISIBLE (-1525 -2275);
FORCEADD OFFPAGE..2
(-1925 -1700);
FORCEPROP 2 LAST $XR0 119 
J 0
(-1736 -1700);
DISPLAY 0.638298 (-1736 -1700);
PAINT MONO (-1736 -1700);
FORCEPROP 2 LAST $XR1 170 
J 0
(-1616 -1700);
DISPLAY 0.638298 (-1616 -1700);
PAINT MONO (-1616 -1700);
FORCEPROP 1 LAST COMMENT_BODY TRUE
J 0
(-1970 -1795);
DISPLAY 0.872340 (-1970 -1795);
PAINT GREEN (-1970 -1795);
DISPLAY INVISIBLE (-1970 -1795);
FORCEPROP 1 LAST OFFPAGE TRUE
J 0
(-1600 -1825);
DISPLAY 0.872340 (-1600 -1825);
PAINT GREEN (-1600 -1825);
DISPLAY INVISIBLE (-1600 -1825);
FORCEPROP 2 LAST CDS_LIB mstr_standard
J 0
(-1925 -1700);
PAINT MONO (-1925 -1700);
DISPLAY INVISIBLE (-1925 -1700);
FORCEPROP 2 LAST PATH I78
J 0
(-1600 -1650);
DISPLAY 1.021277 (-1600 -1650);
PAINT ORANGE (-1600 -1650);
DISPLAY INVISIBLE (-1600 -1650);
FORCEADD OFFPAGE..4
(-1700 -2800);
FORCEPROP 2 LAST $XR0 133 
J 0
(-1484 -2800);
DISPLAY 0.638298 (-1484 -2800);
PAINT MONO (-1484 -2800);
FORCEPROP 2 LAST $XR1 199 
J 0
(-1364 -2800);
DISPLAY 0.638298 (-1364 -2800);
PAINT MONO (-1364 -2800);
FORCEPROP 2 LAST $XR2 119 
J 0
(-1244 -2800);
DISPLAY 0.638298 (-1244 -2800);
PAINT MONO (-1244 -2800);
FORCEPROP 1 LAST COMMENT_BODY TRUE
J 0
(-1725 -2900);
DISPLAY 0.872340 (-1725 -2900);
PAINT GREEN (-1725 -2900);
DISPLAY INVISIBLE (-1725 -2900);
FORCEPROP 1 LAST OFFPAGE TRUE
J 0
(-1375 -2925);
DISPLAY 0.872340 (-1375 -2925);
PAINT GREEN (-1375 -2925);
DISPLAY INVISIBLE (-1375 -2925);
FORCEPROP 2 LAST CDS_LIB mstr_standard
J 0
(-1700 -2800);
PAINT MONO (-1700 -2800);
DISPLAY INVISIBLE (-1700 -2800);
FORCEPROP 2 LAST PATH I80
J 0
(-1525 -2725);
DISPLAY 1.021277 (-1525 -2725);
PAINT ORANGE (-1525 -2725);
DISPLAY INVISIBLE (-1525 -2725);
FORCEADD OFFPAGE..2
(-1675 -2750);
FORCEPROP 2 LAST $XR0 120 
J 0
(-1486 -2750);
DISPLAY 0.638298 (-1486 -2750);
PAINT MONO (-1486 -2750);
FORCEPROP 1 LAST COMMENT_BODY TRUE
J 0
(-1720 -2845);
DISPLAY 0.872340 (-1720 -2845);
PAINT GREEN (-1720 -2845);
DISPLAY INVISIBLE (-1720 -2845);
FORCEPROP 1 LAST OFFPAGE TRUE
J 0
(-1350 -2875);
DISPLAY 0.872340 (-1350 -2875);
PAINT GREEN (-1350 -2875);
DISPLAY INVISIBLE (-1350 -2875);
FORCEPROP 2 LAST CDS_LIB mstr_standard
J 0
(-1675 -2750);
PAINT MONO (-1675 -2750);
DISPLAY INVISIBLE (-1675 -2750);
FORCEPROP 2 LAST PATH I81
J 0
(-1500 -2675);
DISPLAY 1.021277 (-1500 -2675);
PAINT ORANGE (-1500 -2675);
DISPLAY INVISIBLE (-1500 -2675);
FORCEADD RES..1
(-1350 -2600);
FORCEPROP 1 LAST VALUE 0.0
J 2
(-1450 -2650);
DISPLAY 0.617021 (-1450 -2650);
PAINT SKYBLUE (-1450 -2650);
FORCEPROP 1 LAST LOCATION R1T24
J 0
(-1250 -2550);
DISPLAY 0.617021 (-1250 -2550);
PAINT AQUA (-1250 -2550);
FORCEPROP 1 LASTPIN (-1450 -2600) $PN 1
J 0
(-1438 -2588);
DISPLAY 0.617021 (-1438 -2588);
PAINT ORANGE (-1438 -2588);
FORCEPROP 1 LAST TOLERANCE 5%
J 0
(-1225 -2650);
DISPLAY 0.617021 (-1225 -2650);
PAINT SKYBLUE (-1225 -2650);
FORCEPROP 1 LAST PART_NUMBER G21497-005
J 0
(-1275 -2725);
DISPLAY 0.617021 (-1275 -2725);
PAINT BLUE (-1275 -2725);
FORCEPROP 1 LAST PACK_TYPE 0402
J 0
(-975 -2650);
DISPLAY 0.617021 (-975 -2650);
PAINT SKYBLUE (-975 -2650);
FORCEPROP 1 LAST WATTAGE 1/16W
J 2
(-1000 -2650);
DISPLAY 0.617021 (-1000 -2650);
PAINT SKYBLUE (-1000 -2650);
FORCEPROP 1 LASTPIN (-1250 -2600) $PN 2
J 0
(-1288 -2588);
DISPLAY 0.617021 (-1288 -2588);
PAINT ORANGE (-1288 -2588);
FORCEPROP 1 LAST MATERIAL EMPTY
J 0
(-1425 -2550);
DISPLAY 0.617021 (-1425 -2550);
PAINT RED (-1425 -2550);
FORCEPROP 1 LAST PATH I82
J 0
(-1400 -2450);
DISPLAY 0.978723 (-1400 -2450);
PAINT WHITE (-1400 -2450);
DISPLAY INVISIBLE (-1400 -2450);
FORCEPROP 2 LAST SEC_TYPE 0402
J 0
(-1400 -2400);
DISPLAY 1.021277 (-1400 -2400);
PAINT ORANGE (-1400 -2400);
DISPLAY INVISIBLE (-1400 -2400);
FORCEPROP 2 LAST SEC 1
J 0
(-1400 -2400);
PAINT MONO (-1400 -2400);
DISPLAY INVISIBLE (-1400 -2400);
FORCEPROP 2 LAST CDS_LOCATION R1T24
J 0
(-1350 -2575);
DISPLAY 0.617021 (-1350 -2575);
PAINT AQUA (-1350 -2575);
DISPLAY INVISIBLE (-1350 -2575);
FORCEPROP 2 LAST CDS_LIB mstr_discrete
J 0
(-1350 -2600);
PAINT ORANGE (-1350 -2600);
DISPLAY INVISIBLE (-1350 -2600);
FORCEADD OFFPAGE..2
(-625 -2600);
FORCEPROP 2 LAST $XR0 125 
J 0
(-436 -2600);
DISPLAY 0.638298 (-436 -2600);
PAINT MONO (-436 -2600);
FORCEPROP 2 LAST $XR1 121 
J 0
(-316 -2600);
DISPLAY 0.638298 (-316 -2600);
PAINT MONO (-316 -2600);
FORCEPROP 1 LAST COMMENT_BODY TRUE
J 0
(-670 -2695);
DISPLAY 0.872340 (-670 -2695);
PAINT GREEN (-670 -2695);
DISPLAY INVISIBLE (-670 -2695);
FORCEPROP 1 LAST OFFPAGE TRUE
J 0
(-300 -2725);
DISPLAY 0.872340 (-300 -2725);
PAINT GREEN (-300 -2725);
DISPLAY INVISIBLE (-300 -2725);
FORCEPROP 2 LAST PATH I83
J 0
(-300 -2550);
DISPLAY 1.021277 (-300 -2550);
PAINT ORANGE (-300 -2550);
DISPLAY INVISIBLE (-300 -2550);
FORCEPROP 2 LAST CDS_LIB mstr_standard
J 0
(-625 -2600);
PAINT ORANGE (-625 -2600);
DISPLAY INVISIBLE (-625 -2600);
FORCEADD OFFPAGE..2
(-1675 -2650);
FORCEPROP 2 LAST $XR0 119 
J 0
(-1486 -2650);
DISPLAY 0.638298 (-1486 -2650);
PAINT MONO (-1486 -2650);
DISPLAY INVISIBLE (-1486 -2650);
FORCEPROP 2 LAST $XR1 157 
J 0
(-1486 -2650);
DISPLAY 0.638298 (-1486 -2650);
PAINT MONO (-1486 -2650);
DISPLAY INVISIBLE (-1486 -2650);
FORCEPROP 2 LAST $XR2 190 
J 0
(-1486 -2650);
DISPLAY 0.638298 (-1486 -2650);
PAINT MONO (-1486 -2650);
DISPLAY INVISIBLE (-1486 -2650);
FORCEPROP 1 LAST COMMENT_BODY TRUE
J 0
(-1720 -2745);
DISPLAY 0.872340 (-1720 -2745);
PAINT GREEN (-1720 -2745);
DISPLAY INVISIBLE (-1720 -2745);
FORCEPROP 1 LAST OFFPAGE TRUE
J 0
(-1350 -2775);
DISPLAY 0.872340 (-1350 -2775);
PAINT GREEN (-1350 -2775);
DISPLAY INVISIBLE (-1350 -2775);
FORCEPROP 2 LAST CDS_LIB mstr_standard
J 0
(-1675 -2650);
PAINT MONO (-1675 -2650);
DISPLAY INVISIBLE (-1675 -2650);
FORCEPROP 2 LAST PATH I85
J 0
(-1500 -2575);
DISPLAY 1.021277 (-1500 -2575);
PAINT ORANGE (-1500 -2575);
DISPLAY INVISIBLE (-1500 -2575);
FORCEADD RES..1
(-6725 -3150);
FORCEPROP 1 LAST VALUE 0.0
J 2
(-6525 -3150);
DISPLAY 0.617021 (-6525 -3150);
PAINT SKYBLUE (-6525 -3150);
FORCEPROP 1 LAST PACK_TYPE 0402
J 0
(-6575 -3200);
DISPLAY 0.617021 (-6575 -3200);
PAINT SKYBLUE (-6575 -3200);
FORCEPROP 1 LAST LOCATION R6W17
J 0
(-6750 -3125);
DISPLAY 0.617021 (-6750 -3125);
PAINT AQUA (-6750 -3125);
FORCEPROP 1 LAST TOLERANCE 5%
J 0
(-6800 -3200);
DISPLAY 0.617021 (-6800 -3200);
PAINT SKYBLUE (-6800 -3200);
FORCEPROP 1 LAST MATERIAL CHIP
J 0
(-6925 -3125);
DISPLAY 0.617021 (-6925 -3125);
PAINT SKYBLUE (-6925 -3125);
FORCEPROP 1 LASTPIN (-6625 -3150) $PN 2
J 0
(-6663 -3138);
DISPLAY 0.787234 (-6663 -3138);
PAINT ORANGE (-6663 -3138);
DISPLAY INVISIBLE (-6663 -3138);
FORCEPROP 1 LASTPIN (-6825 -3150) $PN 1
J 0
(-6813 -3138);
DISPLAY 0.787234 (-6813 -3138);
PAINT ORANGE (-6813 -3138);
DISPLAY INVISIBLE (-6813 -3138);
FORCEPROP 1 LAST PATH I89
J 0
(-6775 -3000);
DISPLAY 0.978723 (-6775 -3000);
PAINT WHITE (-6775 -3000);
DISPLAY INVISIBLE (-6775 -3000);
FORCEPROP 2 LAST CDS_LIB mstr_discrete
J 0
(-6725 -3150);
PAINT MONO (-6725 -3150);
DISPLAY INVISIBLE (-6725 -3150);
FORCEPROP 0 LAST BOM_COST MIO_USB
J 0
(-6550 -3000);
DISPLAY 1.021277 (-6550 -3000);
PAINT ORANGE (-6550 -3000);
DISPLAY INVISIBLE (-6550 -3000);
FORCEPROP 0 LAST ROOM USB
J 0
(-6550 -3050);
DISPLAY 1.021277 (-6550 -3050);
PAINT ORANGE (-6550 -3050);
DISPLAY INVISIBLE (-6550 -3050);
FORCEPROP 1 LAST PART_NUMBER G21497-005
J 0
(-6650 -3100);
DISPLAY 0.510638 (-6650 -3100);
PAINT BLUE (-6650 -3100);
DISPLAY INVISIBLE (-6650 -3100);
FORCEPROP 1 LAST WATTAGE 1/16W
J 2
(-6750 -3275);
DISPLAY 0.510638 (-6750 -3275);
PAINT SKYBLUE (-6750 -3275);
DISPLAY INVISIBLE (-6750 -3275);
FORCEADD RES..1
(-6700 -3050);
FORCEPROP 1 LAST VALUE 0.0
J 2
(-6525 -3000);
DISPLAY 0.617021 (-6525 -3000);
PAINT SKYBLUE (-6525 -3000);
FORCEPROP 1 LAST TOLERANCE 5%
J 0
(-6825 -3050);
DISPLAY 0.617021 (-6825 -3050);
PAINT SKYBLUE (-6825 -3050);
FORCEPROP 1 LAST LOCATION R6W18
J 0
(-6750 -3000);
DISPLAY 0.617021 (-6750 -3000);
PAINT AQUA (-6750 -3000);
FORCEPROP 1 LAST PACK_TYPE 0402
J 0
(-6600 -3075);
DISPLAY 0.617021 (-6600 -3075);
PAINT SKYBLUE (-6600 -3075);
FORCEPROP 1 LAST MATERIAL CHIP
J 0
(-6925 -3025);
DISPLAY 0.617021 (-6925 -3025);
PAINT SKYBLUE (-6925 -3025);
FORCEPROP 1 LASTPIN (-6600 -3050) $PN 2
J 0
(-6638 -3038);
DISPLAY 0.787234 (-6638 -3038);
PAINT ORANGE (-6638 -3038);
DISPLAY INVISIBLE (-6638 -3038);
FORCEPROP 1 LASTPIN (-6800 -3050) $PN 1
J 0
(-6788 -3038);
DISPLAY 0.787234 (-6788 -3038);
PAINT ORANGE (-6788 -3038);
DISPLAY INVISIBLE (-6788 -3038);
FORCEPROP 1 LAST PATH I90
J 0
(-6750 -2900);
DISPLAY 0.978723 (-6750 -2900);
PAINT WHITE (-6750 -2900);
DISPLAY INVISIBLE (-6750 -2900);
FORCEPROP 0 LAST BOM_COST MIO_USB
J 0
(-6525 -2900);
DISPLAY 1.021277 (-6525 -2900);
PAINT ORANGE (-6525 -2900);
DISPLAY INVISIBLE (-6525 -2900);
FORCEPROP 0 LAST ROOM USB
J 0
(-6525 -2950);
DISPLAY 1.021277 (-6525 -2950);
PAINT ORANGE (-6525 -2950);
DISPLAY INVISIBLE (-6525 -2950);
FORCEPROP 1 LAST PART_NUMBER G21497-005
J 0
(-6625 -3000);
DISPLAY 0.510638 (-6625 -3000);
PAINT BLUE (-6625 -3000);
DISPLAY INVISIBLE (-6625 -3000);
FORCEPROP 1 LAST WATTAGE 1/16W
J 2
(-6725 -3175);
DISPLAY 0.510638 (-6725 -3175);
PAINT SKYBLUE (-6725 -3175);
DISPLAY INVISIBLE (-6725 -3175);
FORCEPROP 2 LAST CDS_LIB mstr_discrete
J 0
(-6700 -3050);
PAINT MONO (-6700 -3050);
DISPLAY INVISIBLE (-6700 -3050);
FORCEADD OFFPAGE..3
R 2
(-7525 -3050);
FORCEPROP 2 LAST $XR0 176 
J 0
(-7805 -3050);
DISPLAY 0.638298 (-7805 -3050);
PAINT MONO (-7805 -3050);
FORCEPROP 2 LAST $XR1 247 
J 0
(-7925 -3050);
DISPLAY 0.638298 (-7925 -3050);
PAINT MONO (-7925 -3050);
FORCEPROP 1 LAST COMMENT_BODY TRUE
J 2
(-7475 -3150);
DISPLAY 1.170213 (-7475 -3150);
PAINT GREEN (-7475 -3150);
DISPLAY INVISIBLE (-7475 -3150);
FORCEPROP 1 LAST OFFPAGE TRUE
J 2
(-7850 -3175);
PAINT GREEN (-7850 -3175);
DISPLAY INVISIBLE (-7850 -3175);
FORCEPROP 2 LAST PATH I91
J 0
(-7475 -2975);
DISPLAY 1.021277 (-7475 -2975);
PAINT ORANGE (-7475 -2975);
DISPLAY INVISIBLE (-7475 -2975);
FORCEPROP 2 LAST CDS_LIB mstr_standard
J 0
(-7525 -3050);
PAINT MONO (-7525 -3050);
DISPLAY INVISIBLE (-7525 -3050);
FORCEPROP 2 LAST BOM_COST SM_CONTROLLER
J 2
(-8000 -3000);
PAINT MONO (-8000 -3000);
DISPLAY INVISIBLE (-8000 -3000);
FORCEPROP 2 LAST ROOM BMC
J 2
(-8000 -3000);
PAINT MONO (-8000 -3000);
DISPLAY INVISIBLE (-8000 -3000);
FORCEADD OFFPAGE..5
(-7550 -3150);
FORCEPROP 2 LAST $XR0 176 
J 0
(-7805 -3150);
DISPLAY 0.638298 (-7805 -3150);
PAINT MONO (-7805 -3150);
FORCEPROP 2 LAST $XR1 247 
J 0
(-7925 -3150);
DISPLAY 0.638298 (-7925 -3150);
PAINT MONO (-7925 -3150);
FORCEPROP 1 LAST COMMENT_BODY TRUE
J 0
(-7450 -3225);
DISPLAY 0.872340 (-7450 -3225);
PAINT GREEN (-7450 -3225);
DISPLAY INVISIBLE (-7450 -3225);
FORCEPROP 1 LAST OFFPAGE TRUE
J 0
(-7225 -3275);
DISPLAY 0.872340 (-7225 -3275);
PAINT GREEN (-7225 -3275);
DISPLAY INVISIBLE (-7225 -3275);
FORCEPROP 2 LAST PATH I92
J 0
(-7500 -3075);
DISPLAY 1.021277 (-7500 -3075);
PAINT ORANGE (-7500 -3075);
DISPLAY INVISIBLE (-7500 -3075);
FORCEPROP 2 LAST CDS_LIB mstr_standard
J 0
(-7550 -3150);
PAINT MONO (-7550 -3150);
DISPLAY INVISIBLE (-7550 -3150);
FORCEADD OFFPAGE..1
(-6625 -3500);
FORCEPROP 2 LAST $XR0 114 
J 0
(-6877 -3500);
DISPLAY 0.638298 (-6877 -3500);
PAINT MONO (-6877 -3500);
FORCEPROP 1 LAST COMMENT_BODY TRUE
J 0
(-6500 -3600);
DISPLAY 0.872340 (-6500 -3600);
PAINT GREEN (-6500 -3600);
DISPLAY INVISIBLE (-6500 -3600);
FORCEPROP 1 LAST OFFPAGE TRUE
J 0
(-6300 -3625);
DISPLAY 0.872340 (-6300 -3625);
PAINT GREEN (-6300 -3625);
DISPLAY INVISIBLE (-6300 -3625);
FORCEPROP 2 LAST PATH I93
J 0
(-6875 -3450);
DISPLAY 1.021277 (-6875 -3450);
PAINT ORANGE (-6875 -3450);
DISPLAY INVISIBLE (-6875 -3450);
FORCEPROP 2 LAST CDS_LIB mstr_standard
J 0
(-6625 -3500);
PAINT ORANGE (-6625 -3500);
DISPLAY INVISIBLE (-6625 -3500);
FORCEPROP 2 LAST ROOM BMC
J 0
(-6875 -3425);
DISPLAY 1.361702 (-6875 -3425);
PAINT ORANGE (-6875 -3425);
DISPLAY INVISIBLE (-6875 -3425);
FORCEPROP 2 LAST BOM_COST SM_CONTROLLER
J 0
(-6175 -3450);
PAINT MONO (-6175 -3450);
DISPLAY INVISIBLE (-6175 -3450);
FORCEADD OFFPAGE..1
(-6625 -3350);
FORCEPROP 2 LAST $XR2 118 
J 0
(-7416 -3350);
DISPLAY 0.638298 (-7416 -3350);
PAINT MONO (-7416 -3350);
FORCEPROP 2 LAST $XR3 190 
J 0
(-7536 -3350);
DISPLAY 0.638298 (-7536 -3350);
PAINT MONO (-7536 -3350);
FORCEPROP 2 LAST $XR0 55 
J 0
(-7176 -3350);
DISPLAY 0.638298 (-7176 -3350);
PAINT MONO (-7176 -3350);
FORCEPROP 2 LAST $XR1 112 
J 0
(-7296 -3350);
DISPLAY 0.638298 (-7296 -3350);
PAINT MONO (-7296 -3350);
FORCEPROP 1 LAST COMMENT_BODY TRUE
J 0
(-6500 -3450);
DISPLAY 0.872340 (-6500 -3450);
PAINT GREEN (-6500 -3450);
DISPLAY INVISIBLE (-6500 -3450);
FORCEPROP 1 LAST OFFPAGE TRUE
J 0
(-6300 -3475);
DISPLAY 0.872340 (-6300 -3475);
PAINT GREEN (-6300 -3475);
DISPLAY INVISIBLE (-6300 -3475);
FORCEPROP 2 LAST PATH I94
J 0
(-7175 -3300);
DISPLAY 1.021277 (-7175 -3300);
PAINT ORANGE (-7175 -3300);
DISPLAY INVISIBLE (-7175 -3300);
FORCEPROP 2 LAST CDS_LIB mstr_standard
J 0
(-6625 -3350);
PAINT MONO (-6625 -3350);
DISPLAY INVISIBLE (-6625 -3350);
FORCEPROP 2 LAST BOM_COST SM_CONTROLLER
J 0
(-6175 -3300);
PAINT MONO (-6175 -3300);
DISPLAY INVISIBLE (-6175 -3300);
FORCEPROP 2 LAST ROOM BMC
J 0
(-6875 -3275);
DISPLAY 1.361702 (-6875 -3275);
PAINT ORANGE (-6875 -3275);
DISPLAY INVISIBLE (-6875 -3275);
FORCEADD AST2520A1-GP-GP..2
(-4375 -2600);
FORCEPROP 1 LAST LOCATION U25W4
J 0
(-5525 -1425);
DISPLAY 0.617021 (-5525 -1425);
PAINT GREEN (-5525 -1425);
FORCEPROP 1 LAST VALUE AST2520A1-GP-GP
J 0
(-5525 -3800);
DISPLAY 0.617021 (-5525 -3800);
PAINT GREEN (-5525 -3800);
FORCEPROP 1 LAST PACK_TYPE ASIC2-GB1
J 0
(-4375 -2600);
DISPLAY 0.617021 (-4375 -2600);
PAINT GREEN (-4375 -2600);
DISPLAY INVISIBLE (-4375 -2600);
FORCEPROP 1 LAST PART_NUMBER 071.2520A.M001
J 0
(-4375 -2600);
DISPLAY 0.617021 (-4375 -2600);
PAINT GREEN (-4375 -2600);
DISPLAY INVISIBLE (-4375 -2600);
FORCEPROP 1 LAST PATH I95
J 0
(-4375 -2600);
DISPLAY 0.617021 (-4375 -2600);
PAINT GREEN (-4375 -2600);
DISPLAY INVISIBLE (-4375 -2600);
FORCEPROP 1 LAST CDS_LMAN_SYM_OUTLINE -1150,1150,1150,-1150
J 0
(-4375 -2600);
DISPLAY 0.468085 (-4375 -2600);
PAINT GREEN (-4375 -2600);
DISPLAY INVISIBLE (-4375 -2600);
FORCEPROP 2 LAST CDS_LIB w_hdl
J 0
(-4375 -2600);
PAINT MONO (-4375 -2600);
DISPLAY INVISIBLE (-4375 -2600);
FORCEADD DNS..2
(-1370 -2605);
PAINT RED (-1370 -2605);
FORCEPROP 1 LAST COMMENT_BODY TRUE
R 1
J 0
(-1295 -2830);
DISPLAY 0.872340 (-1295 -2830);
PAINT GREEN (-1295 -2830);
DISPLAY INVISIBLE (-1295 -2830);
FORCEPROP 2 LAST CDS_LIB mstr_misc
J 0
(-1370 -2605);
PAINT ORANGE (-1370 -2605);
DISPLAY INVISIBLE (-1370 -2605);
FORCEADD INTEL_CORP_BPAGE..1
(-75 -5650);
FORCEPROP 1 LAST CDS_CON_LAST_MODIFIED Tue Dec 01 11:52:04 2015
J 0
(-1500 -5325);
DISPLAY 1.361702 (-1500 -5325);
PAINT GREEN (-1500 -5325);
DISPLAY INVISIBLE (-1500 -5325);
FORCEPROP 1 LAST CUSTOM_TXT_CDS <CURRENT_DESIGN_SHEET> OF <TOTAL_DESIGN_SHEETS>
J 0
(-575 -5625);
PAINT GREEN (-575 -5625);
FORCEPROP 1 LAST CUSTOM_TXT_CDS <CON_LAST_MODIFIED>
J 0
(-2000 -5300);
PAINT GREEN (-2000 -5300);
FORCEPROP 2 LAST CUSTOM_TXT_CDS <XR_PAGE_TITLE>
J 0
(-7965 -400);
DISPLAY 0.638298 (-7965 -400);
PAINT PINK (-7965 -400);
DISPLAY INVISIBLE (-7965 -400);
FORCEPROP 1 LAST SCH_ADDRESS2 P.O. BOX 58119
J 0
(-4050 -5575);
DISPLAY 0.617021 (-4050 -5575);
PAINT GREEN (-4050 -5575);
FORCEPROP 1 LAST SCH_REV 2.420
J 0
(-325 -5500);
DISPLAY 0.978723 (-325 -5500);
PAINT YELLOW (-325 -5500);
FORCEPROP 1 LAST SCH_ADDRESS3 Santa Clara, CA 95052-8119
J 0
(-4050 -5625);
DISPLAY 0.617021 (-4050 -5625);
PAINT GREEN (-4050 -5625);
FORCEPROP 1 LAST SCH_NUMBER H4694802
J 0
(-1375 -5500);
DISPLAY 1.212766 (-1375 -5500);
PAINT YELLOW (-1375 -5500);
FORCEPROP 1 LAST SCH_ADDRESS1 2200 Mission College Blvd.
J 0
(-4050 -5525);
DISPLAY 0.617021 (-4050 -5525);
PAINT GREEN (-4050 -5525);
FORCEPROP 1 LAST SCH_DEPT BESD
J 1
(-4525 -5550);
DISPLAY 1.212766 (-4525 -5550);
PAINT YELLOW (-4525 -5550);
FORCEPROP 1 LAST SCH_TITLE BMC (2 OF 7)
J 0
(-8025 -5600);
DISPLAY 1.212766 (-8025 -5600);
PAINT ORANGE (-8025 -5600);
FORCEPROP 2 LAST PAGE_BORDER TRUE
J 0
(-7965 -400);
DISPLAY 0.851064 (-7965 -400);
PAINT PINK (-7965 -400);
DISPLAY INVISIBLE (-7965 -400);
FORCEPROP 2 LAST CDS_LIB mstr_symbols
J 0
(-75 -5650);
DISPLAY 1.361702 (-75 -5650);
PAINT ORANGE (-75 -5650);
DISPLAY INVISIBLE (-75 -5650);
FORCEPROP 1 LAST COMMENT_BODY TRUE
J 0
(-63 -5638);
DISPLAY 0.617021 (-63 -5638);
PAINT GREEN (-63 -5638);
DISPLAY INVISIBLE (-63 -5638);
FORCEPROP 2 LAST CDS_XR_PAGE_TITLE CR-144 : @BASEBOARD_FAB2_LIB.BASEBOARD_FAB2(SCH_1):PAGE144
J 0
(-7965 -400);
DISPLAY 0.638298 (-7965 -400);
PAINT PINK (-7965 -400);
DISPLAY INVISIBLE (-7965 -400);
WIRE 16 -1 (-1600 -3650)(-1600 -3800);
WIRE 16 -1 (-1600 -3450)(-1600 -3350);
WIRE 16 -1 (-1600 -3350)(-3075 -3350);
FORCEPROP 2 LAST SIG_NAME A_DACRSET
J 0
(-2810 -3340);
DISPLAY 0.680851 (-2810 -3340);
PAINT ORANGE (-2810 -3340);
FORCEPROP 2 LASTPROP $XRERR UNIQUE?
J 0
(-3050 -3340);
DISPLAY 0.638298 (-3050 -3340);
PAINT MONO (-3050 -3340);
DISPLAY INVISIBLE (-3050 -3340);
WIRE 16 -1 (-6575 -3650)(-5675 -3650);
FORCEPROP 0 LAST SIG_NAME IRQ_PVDDQ_GHJ_VRHOT_LVT3_N
J 0
(-6525 -3640);
DISPLAY 0.680851 (-6525 -3640);
PAINT ORANGE (-6525 -3640);
WIRE 16 -1 (-6825 -3150)(-7500 -3150);
FORCEPROP 2 LAST SIG_NAME SMB_IPMB_3V3AUX_SCL
J 0
(-7410 -3140);
DISPLAY 0.680851 (-7410 -3140);
PAINT ORANGE (-7410 -3140);
WIRE 16 -1 (-6800 -3050)(-7475 -3050);
FORCEPROP 2 LAST SIG_NAME SMB_IPMB_3V3AUX_SDA
J 0
(-7435 -3040);
DISPLAY 0.680851 (-7435 -3040);
PAINT ORANGE (-7435 -3040);
WIRE 16 -1 (-5675 -2900)(-6825 -2900);
FORCEPROP 2 LAST SIG_NAME TP_SMB_STORAGE_BP_3V3AUX_SDA
J 0
(-6735 -2890);
DISPLAY 0.680851 (-6735 -2890);
PAINT ORANGE (-6735 -2890);
FORCEPROP 2 LASTPROP $XRERR UNIQUE?
J 0
(-7065 -2900);
DISPLAY 0.638298 (-7065 -2900);
PAINT MONO (-7065 -2900);
DISPLAY INVISIBLE (-7065 -2900);
WIRE 16 -1 (-5675 -2950)(-6825 -2950);
FORCEPROP 2 LAST SIG_NAME TP_SMB_STORAGE_BP_3V3AUX_SCL
J 0
(-6735 -2940);
DISPLAY 0.680851 (-6735 -2940);
PAINT ORANGE (-6735 -2940);
FORCEPROP 2 LASTPROP $XRERR UNIQUE?
J 0
(-7065 -2950);
DISPLAY 0.638298 (-7065 -2950);
PAINT MONO (-7065 -2950);
DISPLAY INVISIBLE (-7065 -2950);
WIRE 16 -1 (-5675 -3050)(-6600 -3050);
FORCEPROP 0 LAST SIG_NAME SMB_IPMB_3V3AUX_SDA_R
J 0
(-6460 -3040);
DISPLAY 0.680851 (-6460 -3040);
PAINT ORANGE (-6460 -3040);
FORCEPROP 2 LASTPROP $XRERR UNIQUE?
J 0
(-6700 -3040);
DISPLAY 0.638298 (-6700 -3040);
PAINT MONO (-6700 -3040);
DISPLAY INVISIBLE (-6700 -3040);
WIRE 16 -1 (-6575 -3600)(-5675 -3600);
FORCEPROP 2 LAST SIG_NAME PWRGD_SYS_PWROK
J 2
(-6050 -3590);
DISPLAY 0.680851 (-6050 -3590);
PAINT ORANGE (-6050 -3590);
WIRE 16 -1 (-3075 -3300)(-1775 -3300);
FORCEPROP 2 LAST SIG_NAME TP_DACB
J 0
(-2810 -3290);
DISPLAY 0.680851 (-2810 -3290);
PAINT ORANGE (-2810 -3290);
FORCEPROP 2 LASTPROP $XRERR UNIQUE?
J 0
(-1745 -3300);
DISPLAY 0.638298 (-1745 -3300);
PAINT MONO (-1745 -3300);
DISPLAY INVISIBLE (-1745 -3300);
WIRE 16 -1 (-3075 -3150)(-1675 -3150);
FORCEPROP 2 LAST SIG_NAME TP_JTAG_BMC_RTCK
J 2
(-2000 -3140);
DISPLAY 0.680851 (-2000 -3140);
PAINT ORANGE (-2000 -3140);
FORCEPROP 2 LASTPROP $XRERR UNIQUE?
J 0
(-1645 -3150);
DISPLAY 0.638298 (-1645 -3150);
PAINT MONO (-1645 -3150);
DISPLAY INVISIBLE (-1645 -3150);
WIRE 16 -1 (-3075 -3250)(-1775 -3250);
FORCEPROP 2 LAST SIG_NAME TP_DACG
J 0
(-2810 -3240);
DISPLAY 0.680851 (-2810 -3240);
PAINT ORANGE (-2810 -3240);
FORCEPROP 2 LASTPROP $XRERR UNIQUE?
J 0
(-1745 -3250);
DISPLAY 0.638298 (-1745 -3250);
PAINT MONO (-1745 -3250);
DISPLAY INVISIBLE (-1745 -3250);
WIRE 16 -1 (-3075 -2800)(-1750 -2800);
FORCEPROP 0 LAST $PHYS_NET_NAME IRQ_HSC_FAULT_N
J 0
(-1750 -2714);
PAINT MONO (-1750 -2714);
DISPLAY INVISIBLE (-1750 -2714);
FORCEPROP 0 LAST CDS_PHYS_NET_NAME IRQ_HSC_FAULT_N
J 0
(-1750 -2761);
PAINT MONO (-1750 -2761);
DISPLAY INVISIBLE (-1750 -2761);
FORCEPROP 2 LAST SIG_NAME IRQ_HSC_FAULT_N
J 2
(-2400 -2790);
DISPLAY 0.680851 (-2400 -2790);
PAINT ORANGE (-2400 -2790);
WIRE 16 -1 (-3075 -2750)(-1725 -2750);
FORCEPROP 0 LAST PHYS_NET_NAME FM_BIOS_MRC_DEBUG_MSG_DIS_N
J 0
(-1800 -2664);
PAINT MONO (-1800 -2664);
DISPLAY INVISIBLE (-1800 -2664);
FORCEPROP 0 LAST CDS_PHYS_NET_NAME FM_BIOS_MRC_DEBUG_MSG_DIS_N
J 0
(-1800 -2711);
PAINT MONO (-1800 -2711);
DISPLAY INVISIBLE (-1800 -2711);
FORCEPROP 2 LAST SIG_NAME FM_BIOS_MRC_DEBUG_MSG_DIS_N
J 2
(-2075 -2740);
DISPLAY 0.680851 (-2075 -2740);
PAINT ORANGE (-2075 -2740);
WIRE 16 -1 (-3075 -2650)(-1725 -2650);
FORCEPROP 0 LAST PHYS_NET_NAME FM_BMC_CPLD_GPO
J 0
(-3075 -2564);
PAINT MONO (-3075 -2564);
DISPLAY INVISIBLE (-3075 -2564);
FORCEPROP 0 LAST CDS_PHYS_NET_NAME FM_BMC_CPLD_GPO
J 0
(-3075 -2611);
PAINT MONO (-3075 -2611);
DISPLAY INVISIBLE (-3075 -2611);
FORCEPROP 0 LAST SIG_NAME FM_BMC_CPLD_GPO
J 0
(-2825 -2640);
DISPLAY 0.680851 (-2825 -2640);
PAINT ORANGE (-2825 -2640);
WIRE 16 -1 (-3075 -2600)(-1450 -2600);
FORCEPROP 2 LAST SIG_NAME FM_FLASH_DESC_OVERRIDE_R
J 0
(-2835 -2590);
DISPLAY 0.680851 (-2835 -2590);
PAINT ORANGE (-2835 -2590);
FORCEPROP 2 LASTPROP $XRERR UNIQUE?
J 0
(-3075 -2590);
DISPLAY 0.638298 (-3075 -2590);
PAINT MONO (-3075 -2590);
DISPLAY INVISIBLE (-3075 -2590);
WIRE 16 -1 (-3075 -2500)(-1725 -2500);
FORCEPROP 0 LAST CDS_PHYS_NET_NAME FM_CPU_BMC_INIT
J 0
(-2085 -2461);
PAINT MONO (-2085 -2461);
DISPLAY INVISIBLE (-2085 -2461);
FORCEPROP 2 LAST SIG_NAME FM_CPU_BMC_INIT
J 0
(-2835 -2490);
DISPLAY 0.680851 (-2835 -2490);
PAINT ORANGE (-2835 -2490);
WIRE 16 -1 (-3075 -2450)(-1750 -2450);
FORCEPROP 2 LAST SIG_NAME FM_SOL_UART_CH_SEL
J 0
(-2835 -2440);
DISPLAY 0.680851 (-2835 -2440);
PAINT ORANGE (-2835 -2440);
WIRE 16 -1 (-3075 -2300)(-1750 -2300);
FORCEPROP 0 LAST SIG_NAME IRQ_PVDDQ_DEF_VRHOT_LVT3_N
J 0
(-2825 -2290);
DISPLAY 0.680851 (-2825 -2290);
PAINT ORANGE (-2825 -2290);
WIRE 16 -1 (-3075 -2200)(-1600 -2200);
FORCEPROP 2 LAST SIG_NAME SGPIO_BMC_CLK_R
J 0
(-2825 -2190);
DISPLAY 0.680851 (-2825 -2190);
PAINT ORANGE (-2825 -2190);
FORCEPROP 2 LASTPROP $XRERR UNIQUE?
J 0
(-3065 -2190);
DISPLAY 0.638298 (-3065 -2190);
PAINT MONO (-3065 -2190);
DISPLAY INVISIBLE (-3065 -2190);
WIRE 16 -1 (-3075 -2150)(-1575 -2150);
FORCEPROP 2 LAST SIG_NAME SGPIO_BMC_LD_R_N
J 0
(-2825 -2140);
DISPLAY 0.680851 (-2825 -2140);
PAINT ORANGE (-2825 -2140);
FORCEPROP 2 LASTPROP $XRERR UNIQUE?
J 0
(-3065 -2140);
DISPLAY 0.638298 (-3065 -2140);
PAINT MONO (-3065 -2140);
DISPLAY INVISIBLE (-3065 -2140);
WIRE 16 -1 (-3075 -2050)(-1575 -2050);
FORCEPROP 2 LAST SIG_NAME SGPIO_BMC_DOUT_R
J 0
(-2800 -2040);
DISPLAY 0.680851 (-2800 -2040);
PAINT ORANGE (-2800 -2040);
FORCEPROP 2 LASTPROP $XRERR UNIQUE?
J 0
(-3040 -2040);
DISPLAY 0.638298 (-3040 -2040);
PAINT MONO (-3040 -2040);
DISPLAY INVISIBLE (-3040 -2040);
WIRE 16 -1 (-2000 -2000)(-3075 -2000);
FORCEPROP 2 LAST SIG_NAME SGPIO_BMC_DIN
J 2
(-2475 -1990);
DISPLAY 0.680851 (-2475 -1990);
PAINT ORANGE (-2475 -1990);
WIRE 16 -1 (-3075 -1900)(-2000 -1900);
FORCEPROP 2 LAST SIG_NAME FM_CPU_ERR2_LVT3_N
J 0
(-2810 -1890);
DISPLAY 0.680851 (-2810 -1890);
PAINT ORANGE (-2810 -1890);
WIRE 16 -1 (-3075 -1850)(-2000 -1850);
FORCEPROP 2 LAST SIG_NAME FM_CPU_CATERR_LVT3_N
J 2
(-2275 -1840);
DISPLAY 0.680851 (-2275 -1840);
PAINT ORANGE (-2275 -1840);
WIRE 16 -1 (-3075 -1750)(-2000 -1750);
FORCEPROP 2 LAST SIG_NAME FM_PCH_BMC_THERMTRIP_N
J 2
(-2225 -1740);
DISPLAY 0.680851 (-2225 -1740);
PAINT ORANGE (-2225 -1740);
WIRE 16 -1 (-3075 -1700)(-1975 -1700);
FORCEPROP 0 LAST CDS_PHYS_NET_NAME FM_FAST_PROCHOT_EN_N
J 0
(-2775 -1661);
PAINT MONO (-2775 -1661);
DISPLAY INVISIBLE (-2775 -1661);
FORCEPROP 2 LAST SIG_NAME FM_FAST_PROCHOT_EN_N
J 0
(-2825 -1690);
DISPLAY 0.680851 (-2825 -1690);
PAINT ORANGE (-2825 -1690);
WIRE 16 -1 (-3075 -2350)(-1750 -2350);
FORCEPROP 0 LAST PHYS_NET_NAME IRQ_DIMM_SAVE_LVT3_N
J 0
(-3085 -2264);
PAINT MONO (-3085 -2264);
DISPLAY INVISIBLE (-3085 -2264);
FORCEPROP 0 LAST CDS_PHYS_NET_NAME IRQ_DIMM_SAVE_LVT3_N
J 0
(-3085 -2311);
PAINT MONO (-3085 -2311);
DISPLAY INVISIBLE (-3085 -2311);
FORCEPROP 2 LAST SIG_NAME IRQ_DIMM_SAVE_LVT3_N
J 0
(-2810 -2340);
DISPLAY 0.680851 (-2810 -2340);
PAINT ORANGE (-2810 -2340);
WIRE 16 -1 (-1775 -3000)(-3075 -3000);
FORCEPROP 2 LAST SIG_NAME JTAG_BMC_TMS
J 2
(-2075 -2990);
DISPLAY 0.680851 (-2075 -2990);
PAINT ORANGE (-2075 -2990);
WIRE 16 -1 (-1775 -2950)(-3075 -2950);
FORCEPROP 2 LAST SIG_NAME JTAG_BMC_TCK
J 2
(-2075 -2940);
DISPLAY 0.680851 (-2075 -2940);
PAINT ORANGE (-2075 -2940);
WIRE 16 -1 (-3075 -3200)(-1775 -3200);
FORCEPROP 2 LAST SIG_NAME TP_DACR
J 0
(-2810 -3190);
DISPLAY 0.680851 (-2810 -3190);
PAINT ORANGE (-2810 -3190);
FORCEPROP 2 LASTPROP $XRERR UNIQUE?
J 0
(-1745 -3200);
DISPLAY 0.638298 (-1745 -3200);
PAINT MONO (-1745 -3200);
DISPLAY INVISIBLE (-1745 -3200);
WIRE 16 -1 (-1375 -2050)(-725 -2050);
FORCEPROP 2 LAST SIG_NAME SGPIO_BMC_DOUT
J 2
(-750 -2040);
DISPLAY 0.617021 (-750 -2040);
PAINT ORANGE (-750 -2040);
WIRE 16 -1 (-1375 -2150)(-725 -2150);
FORCEPROP 2 LAST SIG_NAME SGPIO_BMC_LD_N
J 2
(-700 -2140);
DISPLAY 0.617021 (-700 -2140);
PAINT ORANGE (-700 -2140);
WIRE 16 -1 (-1400 -2200)(-725 -2200);
FORCEPROP 2 LAST SIG_NAME SGPIO_BMC_CLK
J 2
(-750 -2190);
DISPLAY 0.617021 (-750 -2190);
PAINT ORANGE (-750 -2190);
WIRE 16 -1 (-1250 -2600)(-675 -2600);
FORCEPROP 2 LAST SIG_NAME FM_FLASH_DESC_OVERRIDE
J 0
(-1210 -2590);
DISPLAY 0.617021 (-1210 -2590);
PAINT ORANGE (-1210 -2590);
WIRE 16 -1 (-1775 -2900)(-3075 -2900);
FORCEPROP 2 LAST SIG_NAME JTAG_BMC_TRST_N
J 2
(-2325 -2890);
DISPLAY 0.680851 (-2325 -2890);
PAINT ORANGE (-2325 -2890);
WIRE 16 -1 (-1775 -3050)(-3075 -3050);
FORCEPROP 2 LAST SIG_NAME JTAG_BMC_TDI
J 2
(-2025 -3040);
DISPLAY 0.680851 (-2025 -3040);
PAINT ORANGE (-2025 -3040);
WIRE 16 -1 (-1750 -3100)(-3075 -3100);
FORCEPROP 2 LAST SIG_NAME JTAG_BMC_TDO
J 2
(-2075 -3090);
DISPLAY 0.680851 (-2075 -3090);
PAINT ORANGE (-2075 -3090);
WIRE 16 -1 (-5775 -3150)(-5775 -3100);
WIRE 16 -1 (-5775 -3150)(-6625 -3150);
FORCEPROP 2 LAST SIG_NAME SMB_IPMB_3V3AUX_SCL_R
J 0
(-6460 -3140);
DISPLAY 0.680851 (-6460 -3140);
PAINT ORANGE (-6460 -3140);
FORCEPROP 2 LASTPROP $XRERR UNIQUE?
J 0
(-6700 -3140);
DISPLAY 0.638298 (-6700 -3140);
PAINT MONO (-6700 -3140);
DISPLAY INVISIBLE (-6700 -3140);
WIRE 16 -1 (-5775 -3100)(-5675 -3100);
WIRE 16 -1 (-5675 -2800)(-6600 -2800);
FORCEPROP 0 LAST SIG_NAME SMB_VR_STBY_LVC3_SCL_R
J 0
(-6525 -2790);
DISPLAY 0.680851 (-6525 -2790);
PAINT ORANGE (-6525 -2790);
WIRE 16 -1 (-6600 -3550)(-5675 -3550);
FORCEPROP 2 LAST SIG_NAME IRQ_BMC_PCH_SMI_LPC_N
J 2
(-5975 -3540);
DISPLAY 0.680851 (-5975 -3540);
PAINT ORANGE (-5975 -3540);
WIRE 16 -1 (-6575 -3500)(-5675 -3500);
FORCEPROP 0 LAST SIG_NAME CLK_48M_USB_BMC
J 0
(-6450 -3490);
DISPLAY 0.680851 (-6450 -3490);
PAINT ORANGE (-6450 -3490);
WIRE 16 -1 (-6575 -3450)(-5675 -3450);
FORCEPROP 2 LAST SIG_NAME FM_CPU0_SKTOCC_LVT3_N
J 0
(-6460 -3440);
DISPLAY 0.680851 (-6460 -3440);
PAINT ORANGE (-6460 -3440);
WIRE 16 -1 (-5675 -3400)(-6575 -3400);
FORCEPROP 2 LAST SIG_NAME FM_MP_PS_FAIL_N
J 0
(-6460 -3390);
DISPLAY 0.680851 (-6460 -3390);
PAINT ORANGE (-6460 -3390);
WIRE 16 -1 (-6575 -3350)(-5675 -3350);
FORCEPROP 2 LAST SIG_NAME FM_CPU1_SKTOCC_LVT3_N
J 0
(-6460 -3340);
DISPLAY 0.680851 (-6460 -3340);
PAINT ORANGE (-6460 -3340);
WIRE 16 -1 (-6575 -3300)(-5675 -3300);
FORCEPROP 2 LAST SIG_NAME PWRGD_PCH_PWROK
J 2
(-6050 -3290);
DISPLAY 0.680851 (-6050 -3290);
PAINT ORANGE (-6050 -3290);
WIRE 16 -1 (-5675 -2650)(-6600 -2650);
FORCEPROP 0 LAST SIG_NAME SMB_HOST_STBY_LVC3_SCL_R
J 0
(-6525 -2640);
DISPLAY 0.680851 (-6525 -2640);
PAINT ORANGE (-6525 -2640);
WIRE 16 -1 (-5675 -2600)(-6575 -2600);
FORCEPROP 0 LAST SIG_NAME SMB_HOST_STBY_LVC3_SDA_R
J 0
(-6525 -2590);
DISPLAY 0.680851 (-6525 -2590);
PAINT ORANGE (-6525 -2590);
WIRE 16 -1 (-5675 -2750)(-6575 -2750);
FORCEPROP 0 LAST SIG_NAME SMB_VR_STBY_LVC3_SDA_R
J 0
(-6525 -2740);
DISPLAY 0.680851 (-6525 -2740);
PAINT ORANGE (-6525 -2740);
WIRE 16 -1 (-5675 -2500)(-6600 -2500);
FORCEPROP 0 LAST SIG_NAME SMB_SENSOR_BMC_STBY_LVC3_SCL
J 0
(-6525 -2490);
DISPLAY 0.680851 (-6525 -2490);
PAINT ORANGE (-6525 -2490);
WIRE 16 -1 (-5675 -2450)(-6575 -2450);
FORCEPROP 0 LAST SIG_NAME SMB_SENSOR_BMC_STBY_LVC3_SDA
J 0
(-6525 -2440);
DISPLAY 0.680851 (-6525 -2440);
PAINT ORANGE (-6525 -2440);
WIRE 16 -1 (-5675 -2300)(-6575 -2300);
FORCEPROP 0 LAST SIG_NAME SMB_SMLINK0_STBY_LVC3_SDA_R
J 0
(-6525 -2290);
DISPLAY 0.680851 (-6525 -2290);
PAINT ORANGE (-6525 -2290);
WIRE 16 -1 (-5675 -2350)(-6600 -2350);
FORCEPROP 0 LAST SIG_NAME SMB_SMLINK0_STBY_LVC3_SCL_R
J 0
(-6525 -2340);
DISPLAY 0.680851 (-6525 -2340);
PAINT ORANGE (-6525 -2340);
WIRE 16 -1 (-5675 -2150)(-6575 -2150);
FORCEPROP 0 LAST SIG_NAME SMB_OCP_FRU_STBY_LVC3_SDA_R
J 0
(-6550 -2140);
DISPLAY 0.680851 (-6550 -2140);
PAINT ORANGE (-6550 -2140);
WIRE 16 -1 (-6600 -2200)(-5675 -2200);
FORCEPROP 0 LAST SIG_NAME SMB_OCP_FRU_STBY_LVC3_SCL_R
J 0
(-6550 -2190);
DISPLAY 0.680851 (-6550 -2190);
PAINT ORANGE (-6550 -2190);
WIRE 16 -1 (-6575 -2050)(-5675 -2050);
FORCEPROP 0 LAST SIG_NAME SMB_BMC_PMBUS_STBY_LVC3_SCL_R
J 0
(-6550 -2040);
DISPLAY 0.680851 (-6550 -2040);
PAINT ORANGE (-6550 -2040);
WIRE 16 -1 (-5675 -2000)(-6575 -2000);
FORCEPROP 0 LAST SIG_NAME SMB_BMC_PMBUS_STBY_LVC3_SDA_R
J 0
(-6550 -1990);
DISPLAY 0.680851 (-6550 -1990);
PAINT ORANGE (-6550 -1990);
WIRE 16 -1 (-5675 -1900)(-6600 -1900);
FORCEPROP 0 LAST SIG_NAME SMB_SLOTX24_STBY_LVC3_SCL_R
J 0
(-6550 -1890);
DISPLAY 0.680851 (-6550 -1890);
PAINT ORANGE (-6550 -1890);
WIRE 16 -1 (-5675 -1850)(-6575 -1850);
FORCEPROP 0 LAST SIG_NAME SMB_SLOTX24_STBY_LVC3_SDA_R
J 0
(-6550 -1840);
DISPLAY 0.680851 (-6550 -1840);
PAINT ORANGE (-6550 -1840);
WIRE 16 -1 (-5675 -1750)(-6575 -1750);
FORCEPROP 0 LAST SIG_NAME SMB_OCP_LAN_STBY_LVC3_SCL_R
J 0
(-6550 -1740);
DISPLAY 0.680851 (-6550 -1740);
PAINT ORANGE (-6550 -1740);
WIRE 16 -1 (-6575 -1700)(-5675 -1700);
FORCEPROP 0 LAST SIG_NAME SMB_OCP_LAN_STBY_LVC3_SDA_R
J 0
(-6550 -1690);
DISPLAY 0.680851 (-6550 -1690);
PAINT ORANGE (-6550 -1690);
FORCENOTE
ROOM=BMC
(-7975 -5350) 0;
DISPLAY LEFT (-7975 -5350);
DISPLAY 1.595745 (-7975 -5350);
PAINT PURPLE (-7975 -5350);
FORCENOTE
BOM_COST=SM_CONTROLLER
(-8000 -5475) 0;
DISPLAY LEFT (-8000 -5475);
DISPLAY 1.595745 (-8000 -5475);
PAINT PURPLE (-8000 -5475);
QUIT
